(kicad_sch
	(version 20250114)
	(generator "eeschema")
	(generator_version "9.0")
	(paper "A3")
	(title_block
		(title "Kintex 410T devboard")
		(date "2024-04-03")
		(rev "1.1.2")
	)
	(text "NOTE:\nDNP for host-side"
		(exclude_from_sim no)
		(at 290.195 45.72 0)
		(effects
			(font
				(size 1.27 1.27)
			)
			(justify left bottom)
		)
	)
	(text "NOTE:\nDNP for peripheral-side"
		(exclude_from_sim no)
		(at 274.32 80.01 0)
		(effects
			(font
				(size 1.27 1.27)
			)
			(justify left bottom)
		)
	)
	(text "NOTE: UART RX/TX cross"
		(exclude_from_sim no)
		(at 226.06 214.63 0)
		(effects
			(font
				(size 1.27 1.27)
			)
			(justify left bottom)
		)
	)
	(text "I2C_SDA_OUT"
		(exclude_from_sim no)
		(at 237.49 167.64 0)
		(effects
			(font
				(size 1.27 1.27)
			)
			(justify left bottom)
		)
	)
	(text "DIR HIGH (A > B)\n"
		(exclude_from_sim no)
		(at 252.73 149.225 0)
		(effects
			(font
				(size 1.27 1.27)
			)
			(justify left bottom)
		)
	)
	(text "SPI_SCK\n"
		(exclude_from_sim no)
		(at 286.385 177.8 0)
		(effects
			(font
				(size 1.27 1.27)
			)
			(justify left bottom)
		)
	)
	(text "I2C_SCL"
		(exclude_from_sim no)
		(at 286.385 210.82 0)
		(effects
			(font
				(size 1.27 1.27)
			)
			(justify left bottom)
		)
	)
	(text "SPI_SS\n"
		(exclude_from_sim no)
		(at 226.06 172.72 0)
		(effects
			(font
				(size 1.27 1.27)
			)
			(justify left bottom)
		)
	)
	(text "NOTE:\n4x buffers decoupling. \nPlace close to pins \nTXU0304BQAR - 1 & 14\n74LVC1T45GM - 1 & 6"
		(exclude_from_sim no)
		(at 286.385 242.57 0)
		(effects
			(font
				(size 1.27 1.27)
			)
			(justify left bottom)
		)
	)
	(text "USR_USB"
		(exclude_from_sim no)
		(at 212.09 17.78 0)
		(effects
			(font
				(size 1.27 1.27)
				(thickness 0.5994)
				(bold yes)
			)
			(justify left bottom)
		)
	)
	(text "SPI_SI\n"
		(exclude_from_sim no)
		(at 226.06 170.18 0)
		(effects
			(font
				(size 1.27 1.27)
			)
			(justify left bottom)
		)
	)
	(text "SPI_SCK\n"
		(exclude_from_sim no)
		(at 226.06 165.1 0)
		(effects
			(font
				(size 1.27 1.27)
			)
			(justify left bottom)
		)
	)
	(text "SPI_SS\n"
		(exclude_from_sim no)
		(at 286.385 182.88 0)
		(effects
			(font
				(size 1.27 1.27)
			)
			(justify left bottom)
		)
	)
	(text "1u close to VCC\n100n close to VL"
		(exclude_from_sim no)
		(at 153.67 24.13 0)
		(effects
			(font
				(size 1.27 1.27)
			)
			(justify left bottom)
		)
	)
	(text "BRINGUP CFG SWITCH\nU24 bypass for first DC-DC \nprogramming, when +3V3\nwill not be available yet"
		(exclude_from_sim no)
		(at 224.79 282.575 0)
		(effects
			(font
				(size 1.27 1.27)
			)
			(justify left bottom)
		)
	)
	(text "I2C_SDA_IN"
		(exclude_from_sim no)
		(at 286.385 218.44 0)
		(effects
			(font
				(size 1.27 1.27)
			)
			(justify left bottom)
		)
	)
	(text "NOTE: UART RX/TX cross"
		(exclude_from_sim no)
		(at 225.425 193.04 0)
		(effects
			(font
				(size 1.27 1.27)
			)
			(justify left bottom)
		)
	)
	(text "SPI_SO\n"
		(exclude_from_sim no)
		(at 226.06 167.64 0)
		(effects
			(font
				(size 1.27 1.27)
			)
			(justify left bottom)
		)
	)
	(text "NOTE:\nto prevent \nbackfeeding\nwhile U24 \nbypassing"
		(exclude_from_sim no)
		(at 393.065 196.215 0)
		(effects
			(font
				(size 1.27 1.27)
			)
			(justify right bottom)
		)
	)
	(text "I2C_SDA_IN"
		(exclude_from_sim no)
		(at 237.49 170.18 0)
		(effects
			(font
				(size 1.27 1.27)
			)
			(justify left bottom)
		)
	)
	(text "SPI_SO\n"
		(exclude_from_sim no)
		(at 286.385 180.34 0)
		(effects
			(font
				(size 1.27 1.27)
			)
			(justify left bottom)
		)
	)
	(text "SPI_SI\n"
		(exclude_from_sim no)
		(at 286.385 185.42 0)
		(effects
			(font
				(size 1.27 1.27)
			)
			(justify left bottom)
		)
	)
	(text "I2C_SCL"
		(exclude_from_sim no)
		(at 237.49 165.1 0)
		(effects
			(font
				(size 1.27 1.27)
			)
			(justify left bottom)
		)
	)
	(text "I2C_SDA_OUT"
		(exclude_from_sim no)
		(at 286.385 215.9 0)
		(effects
			(font
				(size 1.27 1.27)
			)
			(justify left bottom)
		)
	)
	(text "USB HOST"
		(exclude_from_sim no)
		(at 13.335 17.145 0)
		(effects
			(font
				(size 1.27 1.27)
				(thickness 0.5994)
				(bold yes)
			)
			(justify left bottom)
		)
	)
	(text "USB DEBUG"
		(exclude_from_sim no)
		(at 13.335 120.65 0)
		(effects
			(font
				(size 1.27 1.27)
				(thickness 0.5994)
				(bold yes)
			)
			(justify left bottom)
		)
	)
	(junction
		(at 341.63 237.49)
		(diameter 0)
		(color 0 0 0 0)
	)
	(junction
		(at 243.84 48.26)
		(diameter 0)
		(color 0 0 0 0)
	)
	(junction
		(at 58.42 212.09)
		(diameter 0)
		(color 0 0 0 0)
	)
	(junction
		(at 400.05 86.36)
		(diameter 0)
		(color 0 0 0 0)
	)
	(junction
		(at 46.99 68.58)
		(diameter 0)
		(color 0 0 0 0)
	)
	(junction
		(at 281.94 264.16)
		(diameter 0)
		(color 0 0 0 0)
	)
	(junction
		(at 321.31 237.49)
		(diameter 0)
		(color 0 0 0 0)
	)
	(junction
		(at 104.14 143.51)
		(diameter 0)
		(color 0 0 0 0)
	)
	(junction
		(at 34.29 245.11)
		(diameter 0)
		(color 0 0 0 0)
	)
	(junction
		(at 350.52 138.43)
		(diameter 0)
		(color 0 0 0 0)
	)
	(junction
		(at 307.34 24.13)
		(diameter 0)
		(color 0 0 0 0)
	)
	(junction
		(at 171.45 234.95)
		(diameter 0)
		(color 0 0 0 0)
	)
	(junction
		(at 337.82 208.28)
		(diameter 0)
		(color 0 0 0 0)
	)
	(junction
		(at 73.66 184.15)
		(diameter 0)
		(color 0 0 0 0)
	)
	(junction
		(at 171.45 143.51)
		(diameter 0)
		(color 0 0 0 0)
	)
	(junction
		(at 123.19 234.95)
		(diameter 0)
		(color 0 0 0 0)
	)
	(junction
		(at 353.06 73.66)
		(diameter 0)
		(color 0 0 0 0)
	)
	(junction
		(at 125.73 143.51)
		(diameter 0)
		(color 0 0 0 0)
	)
	(junction
		(at 140.97 207.01)
		(diameter 0)
		(color 0 0 0 0)
	)
	(junction
		(at 106.68 85.09)
		(diameter 0)
		(color 0 0 0 0)
	)
	(junction
		(at 62.23 34.29)
		(diameter 0)
		(color 0 0 0 0)
	)
	(junction
		(at 251.46 140.97)
		(diameter 0)
		(color 0 0 0 0)
	)
	(junction
		(at 63.5 165.1)
		(diameter 0)
		(color 0 0 0 0)
	)
	(junction
		(at 312.42 50.8)
		(diameter 0)
		(color 0 0 0 0)
	)
	(junction
		(at 331.47 91.44)
		(diameter 0)
		(color 0 0 0 0)
	)
	(junction
		(at 59.69 39.37)
		(diameter 0)
		(color 0 0 0 0)
	)
	(junction
		(at 287.02 72.39)
		(diameter 0)
		(color 0 0 0 0)
	)
	(junction
		(at 309.88 85.09)
		(diameter 0)
		(color 0 0 0 0)
	)
	(junction
		(at 137.16 229.87)
		(diameter 0)
		(color 0 0 0 0)
	)
	(junction
		(at 252.73 233.68)
		(diameter 0)
		(color 0 0 0 0)
	)
	(junction
		(at 96.52 82.55)
		(diameter 0)
		(color 0 0 0 0)
	)
	(junction
		(at 137.16 143.51)
		(diameter 0)
		(color 0 0 0 0)
	)
	(junction
		(at 77.47 95.25)
		(diameter 0)
		(color 0 0 0 0)
	)
	(junction
		(at 392.43 86.36)
		(diameter 0)
		(color 0 0 0 0)
	)
	(junction
		(at 326.39 40.64)
		(diameter 0)
		(color 0 0 0 0)
	)
	(junction
		(at 149.86 25.4)
		(diameter 0)
		(color 0 0 0 0)
	)
	(junction
		(at 125.73 125.73)
		(diameter 0)
		(color 0 0 0 0)
	)
	(junction
		(at 246.38 60.96)
		(diameter 0)
		(color 0 0 0 0)
	)
	(junction
		(at 355.6 217.17)
		(diameter 0)
		(color 0 0 0 0)
	)
	(junction
		(at 110.49 53.34)
		(diameter 0)
		(color 0 0 0 0)
	)
	(junction
		(at 331.47 237.49)
		(diameter 0)
		(color 0 0 0 0)
	)
	(junction
		(at 157.48 25.4)
		(diameter 0)
		(color 0 0 0 0)
	)
	(junction
		(at 360.68 91.44)
		(diameter 0)
		(color 0 0 0 0)
	)
	(junction
		(at 318.77 24.13)
		(diameter 0)
		(color 0 0 0 0)
	)
	(junction
		(at 284.48 50.8)
		(diameter 0)
		(color 0 0 0 0)
	)
	(junction
		(at 312.42 220.98)
		(diameter 0)
		(color 0 0 0 0)
	)
	(junction
		(at 292.1 60.96)
		(diameter 0)
		(color 0 0 0 0)
	)
	(junction
		(at 248.92 58.42)
		(diameter 0)
		(color 0 0 0 0)
	)
	(junction
		(at 127 85.09)
		(diameter 0)
		(color 0 0 0 0)
	)
	(junction
		(at 375.92 237.49)
		(diameter 0)
		(color 0 0 0 0)
	)
	(junction
		(at 115.57 125.73)
		(diameter 0)
		(color 0 0 0 0)
	)
	(junction
		(at 34.29 257.81)
		(diameter 0)
		(color 0 0 0 0)
	)
	(junction
		(at 237.49 60.96)
		(diameter 0)
		(color 0 0 0 0)
	)
	(junction
		(at 382.27 99.06)
		(diameter 0)
		(color 0 0 0 0)
	)
	(junction
		(at 173.99 125.73)
		(diameter 0)
		(color 0 0 0 0)
	)
	(junction
		(at 34.29 251.46)
		(diameter 0)
		(color 0 0 0 0)
	)
	(junction
		(at 57.15 87.63)
		(diameter 0)
		(color 0 0 0 0)
	)
	(junction
		(at 58.42 191.77)
		(diameter 0)
		(color 0 0 0 0)
	)
	(junction
		(at 285.75 60.96)
		(diameter 0)
		(color 0 0 0 0)
	)
	(junction
		(at 21.59 78.74)
		(diameter 0)
		(color 0 0 0 0)
	)
	(junction
		(at 66.04 181.61)
		(diameter 0)
		(color 0 0 0 0)
	)
	(junction
		(at 115.57 143.51)
		(diameter 0)
		(color 0 0 0 0)
	)
	(junction
		(at 36.83 133.35)
		(diameter 0)
		(color 0 0 0 0)
	)
	(junction
		(at 336.55 175.26)
		(diameter 0)
		(color 0 0 0 0)
	)
	(junction
		(at 355.6 24.13)
		(diameter 0)
		(color 0 0 0 0)
	)
	(junction
		(at 64.77 133.35)
		(diameter 0)
		(color 0 0 0 0)
	)
	(junction
		(at 147.32 143.51)
		(diameter 0)
		(color 0 0 0 0)
	)
	(junction
		(at 377.19 210.82)
		(diameter 0)
		(color 0 0 0 0)
	)
	(junction
		(at 294.64 58.42)
		(diameter 0)
		(color 0 0 0 0)
	)
	(junction
		(at 57.15 189.23)
		(diameter 0)
		(color 0 0 0 0)
	)
	(junction
		(at 68.58 189.23)
		(diameter 0)
		(color 0 0 0 0)
	)
	(junction
		(at 377.19 199.39)
		(diameter 0)
		(color 0 0 0 0)
	)
	(junction
		(at 71.12 191.77)
		(diameter 0)
		(color 0 0 0 0)
	)
	(junction
		(at 116.84 167.64)
		(diameter 0)
		(color 0 0 0 0)
	)
	(junction
		(at 240.03 58.42)
		(diameter 0)
		(color 0 0 0 0)
	)
	(junction
		(at 165.1 38.1)
		(diameter 0)
		(color 0 0 0 0)
	)
	(junction
		(at 397.51 237.49)
		(diameter 0)
		(color 0 0 0 0)
	)
	(junction
		(at 288.29 58.42)
		(diameter 0)
		(color 0 0 0 0)
	)
	(junction
		(at 52.07 46.99)
		(diameter 0)
		(color 0 0 0 0)
	)
	(junction
		(at 251.46 50.8)
		(diameter 0)
		(color 0 0 0 0)
	)
	(junction
		(at 162.56 125.73)
		(diameter 0)
		(color 0 0 0 0)
	)
	(junction
		(at 379.73 217.17)
		(diameter 0)
		(color 0 0 0 0)
	)
	(junction
		(at 281.94 278.13)
		(diameter 0)
		(color 0 0 0 0)
	)
	(junction
		(at 160.02 207.01)
		(diameter 0)
		(color 0 0 0 0)
	)
	(junction
		(at 387.35 237.49)
		(diameter 0)
		(color 0 0 0 0)
	)
	(junction
		(at 337.82 138.43)
		(diameter 0)
		(color 0 0 0 0)
	)
	(junction
		(at 104.14 167.64)
		(diameter 0)
		(color 0 0 0 0)
	)
	(junction
		(at 405.13 45.72)
		(diameter 0)
		(color 0 0 0 0)
	)
	(junction
		(at 57.15 41.91)
		(diameter 0)
		(color 0 0 0 0)
	)
	(junction
		(at 171.45 158.75)
		(diameter 0)
		(color 0 0 0 0)
	)
	(junction
		(at 88.9 82.55)
		(diameter 0)
		(color 0 0 0 0)
	)
	(junction
		(at 237.49 78.74)
		(diameter 0)
		(color 0 0 0 0)
	)
	(junction
		(at 30.48 133.35)
		(diameter 0)
		(color 0 0 0 0)
	)
	(no_connect
		(at 214.63 213.36)
	)
	(no_connect
		(at 101.6 255.27)
	)
	(no_connect
		(at 214.63 161.29)
	)
	(no_connect
		(at 194.31 50.8)
	)
	(no_connect
		(at 214.63 182.88)
	)
	(no_connect
		(at 101.6 242.57)
	)
	(no_connect
		(at 214.63 194.31)
	)
	(no_connect
		(at 214.63 180.34)
	)
	(no_connect
		(at 194.31 63.5)
	)
	(no_connect
		(at 266.7 260.35)
	)
	(no_connect
		(at 214.63 191.77)
	)
	(no_connect
		(at 214.63 233.68)
	)
	(no_connect
		(at 194.31 60.96)
	)
	(no_connect
		(at 236.22 71.12)
	)
	(no_connect
		(at 55.88 204.47)
	)
	(no_connect
		(at 214.63 204.47)
	)
	(no_connect
		(at 194.31 68.58)
	)
	(no_connect
		(at 194.31 58.42)
	)
	(no_connect
		(at 214.63 153.67)
	)
	(no_connect
		(at 214.63 223.52)
	)
	(no_connect
		(at 64.77 45.72)
	)
	(no_connect
		(at 55.88 201.93)
	)
	(no_connect
		(at 101.6 240.03)
	)
	(no_connect
		(at 214.63 220.98)
	)
	(no_connect
		(at 194.31 71.12)
	)
	(no_connect
		(at 194.31 66.04)
	)
	(no_connect
		(at 214.63 199.39)
	)
	(no_connect
		(at 194.31 45.72)
	)
	(no_connect
		(at 214.63 158.75)
	)
	(no_connect
		(at 194.31 73.66)
	)
	(no_connect
		(at 266.7 257.81)
	)
	(no_connect
		(at 194.31 53.34)
	)
	(no_connect
		(at 214.63 215.9)
	)
	(no_connect
		(at 214.63 226.06)
	)
	(no_connect
		(at 279.4 257.81)
	)
	(no_connect
		(at 194.31 55.88)
	)
	(no_connect
		(at 194.31 48.26)
	)
	(no_connect
		(at 236.22 68.58)
	)
	(no_connect
		(at 279.4 260.35)
	)
	(no_connect
		(at 331.47 213.36)
	)
	(no_connect
		(at 194.31 40.64)
	)
	(no_connect
		(at 214.63 201.93)
	)
	(no_connect
		(at 194.31 38.1)
	)
	(no_connect
		(at 194.31 43.18)
	)
	(no_connect
		(at 214.63 218.44)
	)
	(no_connect
		(at 214.63 196.85)
	)
	(no_connect
		(at 101.6 234.95)
	)
	(no_connect
		(at 194.31 76.2)
	)
	(no_connect
		(at 101.6 237.49)
	)
	(bus_entry
		(at 148.59 53.34)
		(size -1.27 1.27)
		(stroke
			(width 0)
			(type default)
		)
	)
	(bus_entry
		(at 369.57 46.99)
		(size 1.27 -1.27)
		(stroke
			(width 0)
			(type default)
		)
	)
	(bus_entry
		(at 369.57 49.53)
		(size 1.27 -1.27)
		(stroke
			(width 0)
			(type default)
		)
	)
	(bus_entry
		(at 265.43 185.42)
		(size -1.27 1.27)
		(stroke
			(width 0)
			(type default)
		)
	)
	(bus_entry
		(at 265.43 209.55)
		(size -1.27 1.27)
		(stroke
			(width 0)
			(type default)
		)
	)
	(bus_entry
		(at 369.57 49.53)
		(size -1.27 -1.27)
		(stroke
			(width 0)
			(type default)
		)
	)
	(bus_entry
		(at 298.45 262.89)
		(size -1.27 1.27)
		(stroke
			(width 0)
			(type default)
		)
	)
	(bus_entry
		(at 369.57 181.61)
		(size -1.27 1.27)
		(stroke
			(width 0)
			(type default)
		)
	)
	(bus_entry
		(at 387.35 217.17)
		(size 1.27 -1.27)
		(stroke
			(width 0)
			(type default)
		)
	)
	(bus_entry
		(at 93.98 184.15)
		(size 1.27 -1.27)
		(stroke
			(width 0)
			(type default)
		)
	)
	(bus_entry
		(at 43.18 101.6)
		(size 1.27 -1.27)
		(stroke
			(width 0)
			(type default)
		)
	)
	(bus_entry
		(at 368.3 151.13)
		(size 1.27 -1.27)
		(stroke
			(width 0)
			(type default)
		)
	)
	(bus_entry
		(at 369.57 176.53)
		(size -1.27 1.27)
		(stroke
			(width 0)
			(type default)
		)
	)
	(bus_entry
		(at 369.57 54.61)
		(size -1.27 -1.27)
		(stroke
			(width 0)
			(type default)
		)
	)
	(bus_entry
		(at 369.57 179.07)
		(size -1.27 1.27)
		(stroke
			(width 0)
			(type default)
		)
	)
	(bus_entry
		(at 241.3 261.62)
		(size 1.27 1.27)
		(stroke
			(width 0)
			(type default)
		)
	)
	(bus_entry
		(at 369.57 46.99)
		(size -1.27 -1.27)
		(stroke
			(width 0)
			(type default)
		)
	)
	(bus_entry
		(at 322.58 101.6)
		(size 1.27 -1.27)
		(stroke
			(width 0)
			(type default)
		)
	)
	(bus_entry
		(at 147.32 62.23)
		(size 1.27 -1.27)
		(stroke
			(width 0)
			(type default)
		)
	)
	(bus_entry
		(at 387.35 210.82)
		(size 1.27 -1.27)
		(stroke
			(width 0)
			(type default)
		)
	)
	(bus_entry
		(at 369.57 67.31)
		(size -1.27 -1.27)
		(stroke
			(width 0)
			(type default)
		)
	)
	(bus_entry
		(at 369.57 62.23)
		(size -1.27 -1.27)
		(stroke
			(width 0)
			(type default)
		)
	)
	(bus_entry
		(at 369.57 144.78)
		(size -1.27 1.27)
		(stroke
			(width 0)
			(type default)
		)
	)
	(bus_entry
		(at 147.32 54.61)
		(size -1.27 -1.27)
		(stroke
			(width 0)
			(type default)
		)
	)
	(bus_entry
		(at 147.32 64.77)
		(size 1.27 -1.27)
		(stroke
			(width 0)
			(type default)
		)
	)
	(bus_entry
		(at 265.43 207.01)
		(size -1.27 1.27)
		(stroke
			(width 0)
			(type default)
		)
	)
	(bus_entry
		(at 322.58 101.6)
		(size -1.27 -1.27)
		(stroke
			(width 0)
			(type default)
		)
	)
	(bus_entry
		(at 368.3 148.59)
		(size 1.27 -1.27)
		(stroke
			(width 0)
			(type default)
		)
	)
	(bus_entry
		(at 147.32 69.85)
		(size 1.27 -1.27)
		(stroke
			(width 0)
			(type default)
		)
	)
	(bus_entry
		(at 265.43 187.96)
		(size -1.27 1.27)
		(stroke
			(width 0)
			(type default)
		)
	)
	(bus_entry
		(at 93.98 181.61)
		(size 1.27 -1.27)
		(stroke
			(width 0)
			(type default)
		)
	)
	(bus_entry
		(at 369.57 59.69)
		(size -1.27 -1.27)
		(stroke
			(width 0)
			(type default)
		)
	)
	(bus_entry
		(at 147.32 59.69)
		(size 1.27 -1.27)
		(stroke
			(width 0)
			(type default)
		)
	)
	(bus_entry
		(at 369.57 142.24)
		(size -1.27 1.27)
		(stroke
			(width 0)
			(type default)
		)
	)
	(bus_entry
		(at 369.57 52.07)
		(size -1.27 -1.27)
		(stroke
			(width 0)
			(type default)
		)
	)
	(bus_entry
		(at 148.59 55.88)
		(size -1.27 1.27)
		(stroke
			(width 0)
			(type default)
		)
	)
	(bus_entry
		(at 93.98 165.1)
		(size 1.27 -1.27)
		(stroke
			(width 0)
			(type default)
		)
	)
	(bus_entry
		(at 281.94 143.51)
		(size -1.27 0)
		(stroke
			(width 0)
			(type default)
		)
	)
	(bus_entry
		(at 147.32 67.31)
		(size 1.27 -1.27)
		(stroke
			(width 0)
			(type default)
		)
	)
	(bus_entry
		(at 147.32 57.15)
		(size -1.27 -1.27)
		(stroke
			(width 0)
			(type default)
		)
	)
	(bus_entry
		(at 369.57 64.77)
		(size -1.27 -1.27)
		(stroke
			(width 0)
			(type default)
		)
	)
	(bus_entry
		(at 369.57 184.15)
		(size -1.27 1.27)
		(stroke
			(width 0)
			(type default)
		)
	)
	(bus_entry
		(at 369.57 57.15)
		(size -1.27 -1.27)
		(stroke
			(width 0)
			(type default)
		)
	)
	(bus_entry
		(at 241.3 264.16)
		(size 1.27 1.27)
		(stroke
			(width 0)
			(type default)
		)
	)
	(wire
		(pts
			(xy 236.22 60.96) (xy 237.49 60.96)
		)
		(stroke
			(width 0)
			(type default)
		)
	)
	(wire
		(pts
			(xy 377.19 207.01) (xy 377.19 210.82)
		)
		(stroke
			(width 0)
			(type default)
		)
	)
	(wire
		(pts
			(xy 106.68 92.71) (xy 106.68 96.52)
		)
		(stroke
			(width 0)
			(type default)
		)
	)
	(wire
		(pts
			(xy 346.71 148.59) (xy 368.3 148.59)
		)
		(stroke
			(width 0)
			(type default)
		)
	)
	(wire
		(pts
			(xy 397.51 237.49) (xy 397.51 236.22)
		)
		(stroke
			(width 0)
			(type default)
		)
	)
	(wire
		(pts
			(xy 226.06 231.14) (xy 214.63 231.14)
		)
		(stroke
			(width 0)
			(type default)
		)
	)
	(wire
		(pts
			(xy 259.08 64.77) (xy 259.08 69.85)
		)
		(stroke
			(width 0)
			(type default)
		)
	)
	(wire
		(pts
			(xy 353.06 81.28) (xy 353.06 83.82)
		)
		(stroke
			(width 0)
			(type default)
		)
	)
	(wire
		(pts
			(xy 353.06 72.39) (xy 353.06 73.66)
		)
		(stroke
			(width 0)
			(type default)
		)
	)
	(wire
		(pts
			(xy 365.76 237.49) (xy 365.76 240.03)
		)
		(stroke
			(width 0)
			(type default)
		)
	)
	(wire
		(pts
			(xy 331.47 205.74) (xy 334.01 205.74)
		)
		(stroke
			(width 0)
			(type default)
		)
	)
	(wire
		(pts
			(xy 63.5 162.56) (xy 63.5 165.1)
		)
		(stroke
			(width 0)
			(type default)
		)
	)
	(wire
		(pts
			(xy 173.99 232.41) (xy 171.45 232.41)
		)
		(stroke
			(width 0)
			(type default)
		)
	)
	(wire
		(pts
			(xy 66.04 181.61) (xy 93.98 181.61)
		)
		(stroke
			(width 0)
			(type default)
		)
	)
	(wire
		(pts
			(xy 266.7 270.51) (xy 252.73 270.51)
		)
		(stroke
			(width 0)
			(type default)
		)
	)
	(wire
		(pts
			(xy 152.4 76.2) (xy 166.37 76.2)
		)
		(stroke
			(width 0)
			(type default)
		)
	)
	(wire
		(pts
			(xy 214.63 156.21) (xy 229.87 156.21)
		)
		(stroke
			(width 0)
			(type default)
		)
	)
	(wire
		(pts
			(xy 368.3 172.72) (xy 345.44 172.72)
		)
		(stroke
			(width 0)
			(type default)
		)
	)
	(wire
		(pts
			(xy 377.19 195.58) (xy 377.19 199.39)
		)
		(stroke
			(width 0)
			(type default)
		)
	)
	(wire
		(pts
			(xy 400.05 96.52) (xy 400.05 100.33)
		)
		(stroke
			(width 0)
			(type default)
		)
	)
	(wire
		(pts
			(xy 279.4 265.43) (xy 281.94 265.43)
		)
		(stroke
			(width 0)
			(type default)
		)
	)
	(wire
		(pts
			(xy 34.29 245.11) (xy 34.29 251.46)
		)
		(stroke
			(width 0)
			(type default)
		)
	)
	(wire
		(pts
			(xy 52.07 44.45) (xy 52.07 46.99)
		)
		(stroke
			(width 0)
			(type default)
		)
	)
	(wire
		(pts
			(xy 236.22 43.18) (xy 259.08 43.18)
		)
		(stroke
			(width 0)
			(type default)
		)
	)
	(wire
		(pts
			(xy 34.29 245.11) (xy 53.34 245.11)
		)
		(stroke
			(width 0)
			(type default)
		)
	)
	(wire
		(pts
			(xy 58.42 85.09) (xy 35.56 85.09)
		)
		(stroke
			(width 0)
			(type default)
		)
	)
	(wire
		(pts
			(xy 34.29 251.46) (xy 53.34 251.46)
		)
		(stroke
			(width 0)
			(type default)
		)
	)
	(wire
		(pts
			(xy 379.73 199.39) (xy 379.73 201.93)
		)
		(stroke
			(width 0)
			(type default)
		)
	)
	(wire
		(pts
			(xy 377.19 199.39) (xy 377.19 201.93)
		)
		(stroke
			(width 0)
			(type default)
		)
	)
	(bus
		(pts
			(xy 147.32 69.85) (xy 147.32 71.12)
		)
		(stroke
			(width 0)
			(type default)
		)
	)
	(wire
		(pts
			(xy 121.92 255.27) (xy 123.19 255.27)
		)
		(stroke
			(width 0)
			(type default)
		)
	)
	(polyline
		(pts
			(xy 300.99 81.28) (xy 274.32 81.28)
		)
		(stroke
			(width 0)
			(type default)
		)
	)
	(wire
		(pts
			(xy 251.46 140.97) (xy 252.73 140.97)
		)
		(stroke
			(width 0)
			(type default)
		)
	)
	(wire
		(pts
			(xy 88.9 82.55) (xy 88.9 86.36)
		)
		(stroke
			(width 0)
			(type default)
		)
	)
	(polyline
		(pts
			(xy 374.65 198.12) (xy 393.7 198.12)
		)
		(stroke
			(width 0)
			(type default)
		)
	)
	(wire
		(pts
			(xy 294.64 273.05) (xy 279.4 273.05)
		)
		(stroke
			(width 0)
			(type default)
		)
	)
	(wire
		(pts
			(xy 237.49 81.28) (xy 237.49 78.74)
		)
		(stroke
			(width 0)
			(type default)
		)
	)
	(wire
		(pts
			(xy 58.42 165.1) (xy 63.5 165.1)
		)
		(stroke
			(width 0)
			(type default)
		)
	)
	(wire
		(pts
			(xy 96.52 81.28) (xy 96.52 82.55)
		)
		(stroke
			(width 0)
			(type default)
		)
	)
	(wire
		(pts
			(xy 55.88 184.15) (xy 73.66 184.15)
		)
		(stroke
			(width 0)
			(type default)
		)
	)
	(wire
		(pts
			(xy 146.05 237.49) (xy 146.05 238.76)
		)
		(stroke
			(width 0)
			(type default)
		)
	)
	(wire
		(pts
			(xy 44.45 96.52) (xy 44.45 100.33)
		)
		(stroke
			(width 0)
			(type default)
		)
	)
	(wire
		(pts
			(xy 245.11 245.11) (xy 234.95 245.11)
		)
		(stroke
			(width 0)
			(type default)
		)
	)
	(wire
		(pts
			(xy 165.1 40.64) (xy 165.1 38.1)
		)
		(stroke
			(width 0)
			(type default)
		)
	)
	(wire
		(pts
			(xy 157.48 25.4) (xy 157.48 27.94)
		)
		(stroke
			(width 0)
			(type default)
		)
	)
	(wire
		(pts
			(xy 71.12 191.77) (xy 93.98 191.77)
		)
		(stroke
			(width 0)
			(type default)
		)
	)
	(wire
		(pts
			(xy 350.52 50.8) (xy 368.3 50.8)
		)
		(stroke
			(width 0)
			(type default)
		)
	)
	(wire
		(pts
			(xy 115.57 151.13) (xy 115.57 153.67)
		)
		(stroke
			(width 0)
			(type default)
		)
	)
	(wire
		(pts
			(xy 57.15 189.23) (xy 57.15 194.31)
		)
		(stroke
			(width 0)
			(type default)
		)
	)
	(wire
		(pts
			(xy 331.47 177.8) (xy 340.36 177.8)
		)
		(stroke
			(width 0)
			(type default)
		)
	)
	(wire
		(pts
			(xy 382.27 99.06) (xy 382.27 100.33)
		)
		(stroke
			(width 0)
			(type default)
		)
	)
	(wire
		(pts
			(xy 387.35 245.11) (xy 387.35 246.38)
		)
		(stroke
			(width 0)
			(type default)
		)
	)
	(bus
		(pts
			(xy 323.85 106.68) (xy 322.58 104.14)
		)
		(stroke
			(width 0)
			(type default)
		)
	)
	(bus
		(pts
			(xy 370.84 172.72) (xy 372.11 172.72)
		)
		(stroke
			(width 0)
			(type default)
		)
	)
	(wire
		(pts
			(xy 264.16 275.59) (xy 266.7 275.59)
		)
		(stroke
			(width 0)
			(type default)
		)
	)
	(wire
		(pts
			(xy 152.4 73.66) (xy 166.37 73.66)
		)
		(stroke
			(width 0)
			(type default)
		)
	)
	(wire
		(pts
			(xy 214.63 245.11) (xy 229.87 245.11)
		)
		(stroke
			(width 0)
			(type default)
		)
	)
	(bus
		(pts
			(xy 388.62 215.9) (xy 388.62 209.55)
		)
		(stroke
			(width 0)
			(type default)
		)
	)
	(wire
		(pts
			(xy 214.63 143.51) (xy 229.87 143.51)
		)
		(stroke
			(width 0)
			(type default)
		)
	)
	(wire
		(pts
			(xy 336.55 172.72) (xy 336.55 175.26)
		)
		(stroke
			(width 0)
			(type default)
		)
	)
	(wire
		(pts
			(xy 115.57 133.35) (xy 115.57 134.62)
		)
		(stroke
			(width 0)
			(type default)
		)
	)
	(wire
		(pts
			(xy 345.44 180.34) (xy 368.3 180.34)
		)
		(stroke
			(width 0)
			(type default)
		)
	)
	(wire
		(pts
			(xy 307.34 24.13) (xy 307.34 26.67)
		)
		(stroke
			(width 0)
			(type default)
		)
	)
	(wire
		(pts
			(xy 127 85.09) (xy 127 87.63)
		)
		(stroke
			(width 0)
			(type default)
		)
	)
	(wire
		(pts
			(xy 379.73 207.01) (xy 379.73 217.17)
		)
		(stroke
			(width 0)
			(type default)
		)
	)
	(wire
		(pts
			(xy 165.1 25.4) (xy 165.1 38.1)
		)
		(stroke
			(width 0)
			(type default)
		)
	)
	(polyline
		(pts
			(xy 297.18 161.29) (xy 406.4 161.29)
		)
		(stroke
			(width 0)
			(type dot)
		)
	)
	(wire
		(pts
			(xy 313.69 220.98) (xy 312.42 220.98)
		)
		(stroke
			(width 0)
			(type default)
		)
	)
	(wire
		(pts
			(xy 33.02 78.74) (xy 21.59 78.74)
		)
		(stroke
			(width 0)
			(type default)
		)
	)
	(wire
		(pts
			(xy 68.58 189.23) (xy 93.98 189.23)
		)
		(stroke
			(width 0)
			(type default)
		)
	)
	(wire
		(pts
			(xy 73.66 184.15) (xy 93.98 184.15)
		)
		(stroke
			(width 0)
			(type default)
		)
	)
	(wire
		(pts
			(xy 331.47 218.44) (xy 355.6 218.44)
		)
		(stroke
			(width 0)
			(type default)
		)
	)
	(wire
		(pts
			(xy 67.31 41.91) (xy 69.85 39.37)
		)
		(stroke
			(width 0)
			(type default)
		)
	)
	(wire
		(pts
			(xy 57.15 45.72) (xy 57.15 41.91)
		)
		(stroke
			(width 0)
			(type default)
		)
	)
	(bus
		(pts
			(xy 95.25 154.94) (xy 93.98 153.67)
		)
		(stroke
			(width 0)
			(type default)
		)
	)
	(wire
		(pts
			(xy 147.32 207.01) (xy 140.97 207.01)
		)
		(stroke
			(width 0)
			(type default)
		)
	)
	(wire
		(pts
			(xy 331.47 210.82) (xy 359.41 210.82)
		)
		(stroke
			(width 0)
			(type default)
		)
	)
	(wire
		(pts
			(xy 294.64 53.34) (xy 294.64 58.42)
		)
		(stroke
			(width 0)
			(type default)
		)
	)
	(wire
		(pts
			(xy 346.71 146.05) (xy 368.3 146.05)
		)
		(stroke
			(width 0)
			(type default)
		)
	)
	(wire
		(pts
			(xy 346.71 151.13) (xy 368.3 151.13)
		)
		(stroke
			(width 0)
			(type default)
		)
	)
	(wire
		(pts
			(xy 162.56 133.35) (xy 162.56 134.62)
		)
		(stroke
			(width 0)
			(type default)
		)
	)
	(wire
		(pts
			(xy 300.99 185.42) (xy 313.69 185.42)
		)
		(stroke
			(width 0)
			(type default)
		)
	)
	(polyline
		(pts
			(xy 407.67 252.73) (xy 285.75 252.73)
		)
		(stroke
			(width 0)
			(type default)
		)
	)
	(wire
		(pts
			(xy 63.5 165.1) (xy 93.98 165.1)
		)
		(stroke
			(width 0)
			(type default)
		)
	)
	(bus
		(pts
			(xy 147.32 64.77) (xy 147.32 67.31)
		)
		(stroke
			(width 0)
			(type default)
		)
	)
	(wire
		(pts
			(xy 298.45 151.13) (xy 313.69 151.13)
		)
		(stroke
			(width 0)
			(type default)
		)
	)
	(wire
		(pts
			(xy 214.63 175.26) (xy 224.79 175.26)
		)
		(stroke
			(width 0)
			(type default)
		)
	)
	(bus
		(pts
			(xy 369.57 139.7) (xy 369.57 142.24)
		)
		(stroke
			(width 0)
			(type default)
		)
	)
	(wire
		(pts
			(xy 69.85 39.37) (xy 106.68 39.37)
		)
		(stroke
			(width 0)
			(type default)
		)
	)
	(wire
		(pts
			(xy 337.82 208.28) (xy 337.82 205.74)
		)
		(stroke
			(width 0)
			(type default)
		)
	)
	(wire
		(pts
			(xy 55.88 191.77) (xy 58.42 191.77)
		)
		(stroke
			(width 0)
			(type default)
		)
	)
	(bus
		(pts
			(xy 265.43 205.74) (xy 265.43 207.01)
		)
		(stroke
			(width 0)
			(type default)
		)
	)
	(wire
		(pts
			(xy 58.42 212.09) (xy 58.42 209.55)
		)
		(stroke
			(width 0)
			(type default)
		)
	)
	(polyline
		(pts
			(xy 215.9 194.31) (xy 261.62 194.31)
		)
		(stroke
			(width 0)
			(type default)
		)
	)
	(wire
		(pts
			(xy 325.12 76.2) (xy 309.88 76.2)
		)
		(stroke
			(width 0)
			(type default)
		)
	)
	(wire
		(pts
			(xy 148.59 66.04) (xy 166.37 66.04)
		)
		(stroke
			(width 0)
			(type default)
		)
	)
	(polyline
		(pts
			(xy 13.97 115.57) (xy 407.67 115.57)
		)
		(stroke
			(width 0)
			(type default)
		)
	)
	(wire
		(pts
			(xy 270.51 135.89) (xy 270.51 140.97)
		)
		(stroke
			(width 0)
			(type default)
		)
	)
	(wire
		(pts
			(xy 58.42 133.35) (xy 64.77 133.35)
		)
		(stroke
			(width 0)
			(type default)
		)
	)
	(wire
		(pts
			(xy 243.84 186.69) (xy 264.16 186.69)
		)
		(stroke
			(width 0)
			(type default)
		)
	)
	(wire
		(pts
			(xy 224.79 172.72) (xy 214.63 172.72)
		)
		(stroke
			(width 0)
			(type default)
		)
	)
	(wire
		(pts
			(xy 355.6 24.13) (xy 355.6 26.67)
		)
		(stroke
			(width 0)
			(type default)
		)
	)
	(wire
		(pts
			(xy 341.63 81.28) (xy 341.63 88.9)
		)
		(stroke
			(width 0)
			(type default)
		)
	)
	(wire
		(pts
			(xy 237.49 55.88) (xy 237.49 60.96)
		)
		(stroke
			(width 0)
			(type default)
		)
	)
	(wire
		(pts
			(xy 58.42 191.77) (xy 71.12 191.77)
		)
		(stroke
			(width 0)
			(type default)
		)
	)
	(bus
		(pts
			(xy 298.45 255.27) (xy 297.18 254)
		)
		(stroke
			(width 0)
			(type default)
		)
	)
	(wire
		(pts
			(xy 123.19 234.95) (xy 123.19 242.57)
		)
		(stroke
			(width 0)
			(type default)
		)
	)
	(bus
		(pts
			(xy 298.45 255.27) (xy 298.45 262.89)
		)
		(stroke
			(width 0)
			(type default)
		)
	)
	(wire
		(pts
			(xy 115.57 125.73) (xy 125.73 125.73)
		)
		(stroke
			(width 0)
			(type default)
		)
	)
	(bus
		(pts
			(xy 95.25 154.94) (xy 95.25 163.83)
		)
		(stroke
			(width 0)
			(type default)
		)
	)
	(polyline
		(pts
			(xy 261.62 215.9) (xy 261.62 205.74)
		)
		(stroke
			(width 0)
			(type default)
		)
	)
	(wire
		(pts
			(xy 312.42 53.34) (xy 306.07 53.34)
		)
		(stroke
			(width 0)
			(type default)
		)
	)
	(wire
		(pts
			(xy 154.94 156.21) (xy 173.99 156.21)
		)
		(stroke
			(width 0)
			(type default)
		)
	)
	(bus
		(pts
			(xy 369.57 139.7) (xy 370.84 138.43)
		)
		(stroke
			(width 0)
			(type default)
		)
	)
	(wire
		(pts
			(xy 74.93 95.25) (xy 77.47 95.25)
		)
		(stroke
			(width 0)
			(type default)
		)
	)
	(wire
		(pts
			(xy 326.39 43.18) (xy 326.39 40.64)
		)
		(stroke
			(width 0)
			(type default)
		)
	)
	(wire
		(pts
			(xy 125.73 143.51) (xy 137.16 143.51)
		)
		(stroke
			(width 0)
			(type default)
		)
	)
	(wire
		(pts
			(xy 331.47 175.26) (xy 336.55 175.26)
		)
		(stroke
			(width 0)
			(type default)
		)
	)
	(wire
		(pts
			(xy 270.51 146.05) (xy 270.51 149.86)
		)
		(stroke
			(width 0)
			(type default)
		)
	)
	(wire
		(pts
			(xy 54.61 68.58) (xy 54.61 82.55)
		)
		(stroke
			(width 0)
			(type default)
		)
	)
	(wire
		(pts
			(xy 236.22 50.8) (xy 251.46 50.8)
		)
		(stroke
			(width 0)
			(type default)
		)
	)
	(wire
		(pts
			(xy 251.46 135.89) (xy 251.46 140.97)
		)
		(stroke
			(width 0)
			(type default)
		)
	)
	(wire
		(pts
			(xy 50.8 41.91) (xy 57.15 41.91)
		)
		(stroke
			(width 0)
			(type default)
		)
	)
	(wire
		(pts
			(xy 316.23 100.33) (xy 316.23 85.09)
		)
		(stroke
			(width 0)
			(type default)
		)
	)
	(wire
		(pts
			(xy 251.46 50.8) (xy 251.46 66.04)
		)
		(stroke
			(width 0)
			(type default)
		)
	)
	(bus
		(pts
			(xy 267.97 204.47) (xy 266.7 204.47)
		)
		(stroke
			(width 0)
			(type default)
		)
	)
	(polyline
		(pts
			(xy 297.18 161.29) (xy 297.18 161.29)
		)
		(stroke
			(width 0)
			(type dot)
		)
	)
	(wire
		(pts
			(xy 147.32 81.28) (xy 166.37 81.28)
		)
		(stroke
			(width 0)
			(type default)
		)
	)
	(wire
		(pts
			(xy 312.42 50.8) (xy 312.42 53.34)
		)
		(stroke
			(width 0)
			(type default)
		)
	)
	(wire
		(pts
			(xy 58.42 165.1) (xy 58.42 176.53)
		)
		(stroke
			(width 0)
			(type default)
		)
	)
	(wire
		(pts
			(xy 341.63 74.93) (xy 341.63 76.2)
		)
		(stroke
			(width 0)
			(type default)
		)
	)
	(wire
		(pts
			(xy 331.47 146.05) (xy 341.63 146.05)
		)
		(stroke
			(width 0)
			(type default)
		)
	)
	(wire
		(pts
			(xy 102.87 125.73) (xy 115.57 125.73)
		)
		(stroke
			(width 0)
			(type default)
		)
	)
	(wire
		(pts
			(xy 281.94 264.16) (xy 297.18 264.16)
		)
		(stroke
			(width 0)
			(type default)
		)
	)
	(wire
		(pts
			(xy 151.13 125.73) (xy 162.56 125.73)
		)
		(stroke
			(width 0)
			(type default)
		)
	)
	(wire
		(pts
			(xy 149.86 24.13) (xy 149.86 25.4)
		)
		(stroke
			(width 0)
			(type default)
		)
	)
	(wire
		(pts
			(xy 375.92 237.49) (xy 387.35 237.49)
		)
		(stroke
			(width 0)
			(type default)
		)
	)
	(wire
		(pts
			(xy 73.66 252.73) (xy 73.66 257.81)
		)
		(stroke
			(width 0)
			(type default)
		)
	)
	(wire
		(pts
			(xy 331.47 143.51) (xy 341.63 143.51)
		)
		(stroke
			(width 0)
			(type default)
		)
	)
	(wire
		(pts
			(xy 323.85 100.33) (xy 347.98 100.33)
		)
		(stroke
			(width 0)
			(type default)
		)
	)
	(wire
		(pts
			(xy 252.73 267.97) (xy 266.7 267.97)
		)
		(stroke
			(width 0)
			(type default)
		)
	)
	(wire
		(pts
			(xy 63.5 165.1) (xy 63.5 167.64)
		)
		(stroke
			(width 0)
			(type default)
		)
	)
	(wire
		(pts
			(xy 53.34 238.76) (xy 34.29 238.76)
		)
		(stroke
			(width 0)
			(type default)
		)
	)
	(wire
		(pts
			(xy 279.4 278.13) (xy 281.94 278.13)
		)
		(stroke
			(width 0)
			(type default)
		)
	)
	(wire
		(pts
			(xy 326.39 40.64) (xy 327.66 40.64)
		)
		(stroke
			(width 0)
			(type default)
		)
	)
	(wire
		(pts
			(xy 171.45 143.51) (xy 173.99 143.51)
		)
		(stroke
			(width 0)
			(type default)
		)
	)
	(wire
		(pts
			(xy 214.63 146.05) (xy 229.87 146.05)
		)
		(stroke
			(width 0)
			(type default)
		)
	)
	(wire
		(pts
			(xy 302.26 205.74) (xy 313.69 205.74)
		)
		(stroke
			(width 0)
			(type default)
		)
	)
	(wire
		(pts
			(xy 307.34 24.13) (xy 318.77 24.13)
		)
		(stroke
			(width 0)
			(type default)
		)
	)
	(bus
		(pts
			(xy 369.57 179.07) (xy 369.57 181.61)
		)
		(stroke
			(width 0)
			(type default)
		)
	)
	(wire
		(pts
			(xy 331.47 138.43) (xy 337.82 138.43)
		)
		(stroke
			(width 0)
			(type default)
		)
	)
	(polyline
		(pts
			(xy 313.69 55.88) (xy 313.69 40.64)
		)
		(stroke
			(width 0)
			(type default)
		)
	)
	(wire
		(pts
			(xy 294.64 58.42) (xy 300.99 58.42)
		)
		(stroke
			(width 0)
			(type default)
		)
	)
	(wire
		(pts
			(xy 46.99 68.58) (xy 46.99 71.12)
		)
		(stroke
			(width 0)
			(type default)
		)
	)
	(wire
		(pts
			(xy 121.92 234.95) (xy 123.19 234.95)
		)
		(stroke
			(width 0)
			(type default)
		)
	)
	(wire
		(pts
			(xy 309.88 85.09) (xy 309.88 86.36)
		)
		(stroke
			(width 0)
			(type default)
		)
	)
	(wire
		(pts
			(xy 162.56 125.73) (xy 173.99 125.73)
		)
		(stroke
			(width 0)
			(type default)
		)
	)
	(wire
		(pts
			(xy 149.86 25.4) (xy 149.86 27.94)
		)
		(stroke
			(width 0)
			(type default)
		)
	)
	(bus
		(pts
			(xy 95.25 180.34) (xy 95.25 182.88)
		)
		(stroke
			(width 0)
			(type default)
		)
	)
	(wire
		(pts
			(xy 236.22 48.26) (xy 243.84 48.26)
		)
		(stroke
			(width 0)
			(type default)
		)
	)
	(wire
		(pts
			(xy 69.85 41.91) (xy 106.68 41.91)
		)
		(stroke
			(width 0)
			(type default)
		)
	)
	(wire
		(pts
			(xy 284.48 50.8) (xy 284.48 52.07)
		)
		(stroke
			(width 0)
			(type default)
		)
	)
	(wire
		(pts
			(xy 279.4 262.89) (xy 281.94 262.89)
		)
		(stroke
			(width 0)
			(type default)
		)
	)
	(wire
		(pts
			(xy 50.8 44.45) (xy 52.07 44.45)
		)
		(stroke
			(width 0)
			(type default)
		)
	)
	(wire
		(pts
			(xy 147.32 143.51) (xy 171.45 143.51)
		)
		(stroke
			(width 0)
			(type default)
		)
	)
	(wire
		(pts
			(xy 140.97 215.9) (xy 140.97 218.44)
		)
		(stroke
			(width 0)
			(type default)
		)
	)
	(wire
		(pts
			(xy 276.86 50.8) (xy 284.48 50.8)
		)
		(stroke
			(width 0)
			(type default)
		)
	)
	(wire
		(pts
			(xy 331.47 148.59) (xy 341.63 148.59)
		)
		(stroke
			(width 0)
			(type default)
		)
	)
	(wire
		(pts
			(xy 266.7 273.05) (xy 252.73 273.05)
		)
		(stroke
			(width 0)
			(type default)
		)
	)
	(wire
		(pts
			(xy 115.57 143.51) (xy 125.73 143.51)
		)
		(stroke
			(width 0)
			(type default)
		)
	)
	(wire
		(pts
			(xy 281.94 264.16) (xy 281.94 265.43)
		)
		(stroke
			(width 0)
			(type default)
		)
	)
	(wire
		(pts
			(xy 149.86 25.4) (xy 157.48 25.4)
		)
		(stroke
			(width 0)
			(type default)
		)
	)
	(wire
		(pts
			(xy 397.51 237.49) (xy 397.51 240.03)
		)
		(stroke
			(width 0)
			(type default)
		)
	)
	(wire
		(pts
			(xy 405.13 45.72) (xy 405.13 48.26)
		)
		(stroke
			(width 0)
			(type default)
		)
	)
	(wire
		(pts
			(xy 379.73 91.44) (xy 379.73 99.06)
		)
		(stroke
			(width 0)
			(type default)
		)
	)
	(bus
		(pts
			(xy 241.3 261.62) (xy 241.3 264.16)
		)
		(stroke
			(width 0)
			(type default)
		)
	)
	(bus
		(pts
			(xy 95.25 163.83) (xy 95.25 180.34)
		)
		(stroke
			(width 0)
			(type default)
		)
	)
	(wire
		(pts
			(xy 16.51 133.35) (xy 30.48 133.35)
		)
		(stroke
			(width 0)
			(type default)
		)
	)
	(wire
		(pts
			(xy 307.34 34.29) (xy 307.34 31.75)
		)
		(stroke
			(width 0)
			(type default)
		)
	)
	(wire
		(pts
			(xy 116.84 167.64) (xy 116.84 170.18)
		)
		(stroke
			(width 0)
			(type default)
		)
	)
	(wire
		(pts
			(xy 331.47 182.88) (xy 340.36 182.88)
		)
		(stroke
			(width 0)
			(type default)
		)
	)
	(wire
		(pts
			(xy 353.06 73.66) (xy 359.41 73.66)
		)
		(stroke
			(width 0)
			(type default)
		)
	)
	(wire
		(pts
			(xy 214.63 151.13) (xy 229.87 151.13)
		)
		(stroke
			(width 0)
			(type default)
		)
	)
	(bus
		(pts
			(xy 369.57 67.31) (xy 369.57 71.12)
		)
		(stroke
			(width 0)
			(type default)
		)
	)
	(wire
		(pts
			(xy 154.94 158.75) (xy 171.45 158.75)
		)
		(stroke
			(width 0)
			(type default)
		)
	)
	(wire
		(pts
			(xy 88.9 91.44) (xy 88.9 96.52)
		)
		(stroke
			(width 0)
			(type default)
		)
	)
	(wire
		(pts
			(xy 351.79 215.9) (xy 355.6 215.9)
		)
		(stroke
			(width 0)
			(type default)
		)
	)
	(wire
		(pts
			(xy 120.65 85.09) (xy 127 85.09)
		)
		(stroke
			(width 0)
			(type default)
		)
	)
	(wire
		(pts
			(xy 337.82 208.28) (xy 345.44 208.28)
		)
		(stroke
			(width 0)
			(type default)
		)
	)
	(wire
		(pts
			(xy 163.83 220.98) (xy 163.83 231.14)
		)
		(stroke
			(width 0)
			(type default)
		)
	)
	(polyline
		(pts
			(xy 297.18 127) (xy 406.4 127)
		)
		(stroke
			(width 0)
			(type dot)
		)
	)
	(wire
		(pts
			(xy 104.14 151.13) (xy 104.14 153.67)
		)
		(stroke
			(width 0)
			(type default)
		)
	)
	(wire
		(pts
			(xy 57.15 189.23) (xy 68.58 189.23)
		)
		(stroke
			(width 0)
			(type default)
		)
	)
	(wire
		(pts
			(xy 63.5 173.99) (xy 63.5 172.72)
		)
		(stroke
			(width 0)
			(type default)
		)
	)
	(wire
		(pts
			(xy 55.88 181.61) (xy 66.04 181.61)
		)
		(stroke
			(width 0)
			(type default)
		)
	)
	(polyline
		(pts
			(xy 297.18 127) (xy 297.18 127)
		)
		(stroke
			(width 0)
			(type dot)
		)
	)
	(wire
		(pts
			(xy 334.01 205.74) (xy 334.01 201.93)
		)
		(stroke
			(width 0)
			(type default)
		)
	)
	(bus
		(pts
			(xy 369.57 64.77) (xy 369.57 67.31)
		)
		(stroke
			(width 0)
			(type default)
		)
	)
	(wire
		(pts
			(xy 121.92 247.65) (xy 135.89 247.65)
		)
		(stroke
			(width 0)
			(type default)
		)
	)
	(wire
		(pts
			(xy 137.16 143.51) (xy 137.16 146.05)
		)
		(stroke
			(width 0)
			(type default)
		)
	)
	(wire
		(pts
			(xy 405.13 44.45) (xy 405.13 45.72)
		)
		(stroke
			(width 0)
			(type default)
		)
	)
	(wire
		(pts
			(xy 85.09 252.73) (xy 101.6 252.73)
		)
		(stroke
			(width 0)
			(type default)
		)
	)
	(polyline
		(pts
			(xy 209.55 13.97) (xy 209.55 109.22)
		)
		(stroke
			(width 0)
			(type default)
		)
	)
	(polyline
		(pts
			(xy 285.75 179.07) (xy 285.75 228.6)
		)
		(stroke
			(width 0)
			(type dot)
		)
	)
	(wire
		(pts
			(xy 331.47 81.28) (xy 331.47 91.44)
		)
		(stroke
			(width 0)
			(type default)
		)
	)
	(wire
		(pts
			(xy 121.92 242.57) (xy 123.19 242.57)
		)
		(stroke
			(width 0)
			(type default)
		)
	)
	(wire
		(pts
			(xy 139.7 39.37) (xy 111.76 39.37)
		)
		(stroke
			(width 0)
			(type default)
		)
	)
	(polyline
		(pts
			(xy 13.97 109.22) (xy 203.2 109.22)
		)
		(stroke
			(width 0)
			(type default)
		)
	)
	(wire
		(pts
			(xy 34.29 257.81) (xy 53.34 257.81)
		)
		(stroke
			(width 0)
			(type default)
		)
	)
	(polyline
		(pts
			(xy 374.65 185.42) (xy 374.65 198.12)
		)
		(stroke
			(width 0)
			(type default)
		)
	)
	(polyline
		(pts
			(xy 203.2 13.97) (xy 203.2 109.22)
		)
		(stroke
			(width 0)
			(type default)
		)
	)
	(wire
		(pts
			(xy 359.41 73.66) (xy 359.41 86.36)
		)
		(stroke
			(width 0)
			(type default)
		)
	)
	(wire
		(pts
			(xy 146.05 55.88) (xy 121.92 55.88)
		)
		(stroke
			(width 0)
			(type default)
		)
	)
	(bus
		(pts
			(xy 322.58 101.6) (xy 322.58 104.14)
		)
		(stroke
			(width 0)
			(type default)
		)
	)
	(wire
		(pts
			(xy 161.29 193.04) (xy 173.99 193.04)
		)
		(stroke
			(width 0)
			(type default)
		)
	)
	(wire
		(pts
			(xy 350.52 138.43) (xy 354.33 138.43)
		)
		(stroke
			(width 0)
			(type default)
		)
	)
	(wire
		(pts
			(xy 243.84 48.26) (xy 271.78 48.26)
		)
		(stroke
			(width 0)
			(type default)
		)
	)
	(wire
		(pts
			(xy 287.02 72.39) (xy 288.29 72.39)
		)
		(stroke
			(width 0)
			(type default)
		)
	)
	(wire
		(pts
			(xy 309.88 82.55) (xy 309.88 85.09)
		)
		(stroke
			(width 0)
			(type default)
		)
	)
	(bus
		(pts
			(xy 147.32 54.61) (xy 147.32 57.15)
		)
		(stroke
			(width 0)
			(type default)
		)
	)
	(polyline
		(pts
			(xy 201.93 179.07) (xy 285.75 179.07)
		)
		(stroke
			(width 0)
			(type dot)
		)
	)
	(wire
		(pts
			(xy 52.07 46.99) (xy 52.07 50.8)
		)
		(stroke
			(width 0)
			(type default)
		)
	)
	(wire
		(pts
			(xy 387.35 237.49) (xy 397.51 237.49)
		)
		(stroke
			(width 0)
			(type default)
		)
	)
	(wire
		(pts
			(xy 361.95 88.9) (xy 341.63 88.9)
		)
		(stroke
			(width 0)
			(type default)
		)
	)
	(wire
		(pts
			(xy 292.1 50.8) (xy 300.99 50.8)
		)
		(stroke
			(width 0)
			(type default)
		)
	)
	(wire
		(pts
			(xy 30.48 133.35) (xy 30.48 135.89)
		)
		(stroke
			(width 0)
			(type default)
		)
	)
	(wire
		(pts
			(xy 346.71 143.51) (xy 368.3 143.51)
		)
		(stroke
			(width 0)
			(type default)
		)
	)
	(wire
		(pts
			(xy 72.39 250.19) (xy 72.39 251.46)
		)
		(stroke
			(width 0)
			(type default)
		)
	)
	(bus
		(pts
			(xy 369.57 46.99) (xy 369.57 49.53)
		)
		(stroke
			(width 0)
			(type default)
		)
	)
	(wire
		(pts
			(xy 146.05 125.73) (xy 135.89 125.73)
		)
		(stroke
			(width 0)
			(type default)
		)
	)
	(wire
		(pts
			(xy 234.95 143.51) (xy 252.73 143.51)
		)
		(stroke
			(width 0)
			(type default)
		)
	)
	(wire
		(pts
			(xy 321.31 237.49) (xy 321.31 240.03)
		)
		(stroke
			(width 0)
			(type default)
		)
	)
	(wire
		(pts
			(xy 74.93 87.63) (xy 73.66 87.63)
		)
		(stroke
			(width 0)
			(type default)
		)
	)
	(bus
		(pts
			(xy 147.32 59.69) (xy 147.32 62.23)
		)
		(stroke
			(width 0)
			(type default)
		)
	)
	(wire
		(pts
			(xy 160.02 215.9) (xy 160.02 218.44)
		)
		(stroke
			(width 0)
			(type default)
		)
	)
	(wire
		(pts
			(xy 392.43 96.52) (xy 392.43 100.33)
		)
		(stroke
			(width 0)
			(type default)
		)
	)
	(wire
		(pts
			(xy 50.8 46.99) (xy 52.07 46.99)
		)
		(stroke
			(width 0)
			(type default)
		)
	)
	(wire
		(pts
			(xy 147.32 88.9) (xy 147.32 90.17)
		)
		(stroke
			(width 0)
			(type default)
		)
	)
	(wire
		(pts
			(xy 316.23 85.09) (xy 309.88 85.09)
		)
		(stroke
			(width 0)
			(type default)
		)
	)
	(wire
		(pts
			(xy 251.46 140.97) (xy 251.46 146.05)
		)
		(stroke
			(width 0)
			(type default)
		)
	)
	(wire
		(pts
			(xy 377.19 210.82) (xy 387.35 210.82)
		)
		(stroke
			(width 0)
			(type default)
		)
	)
	(wire
		(pts
			(xy 243.84 210.82) (xy 264.16 210.82)
		)
		(stroke
			(width 0)
			(type default)
		)
	)
	(wire
		(pts
			(xy 242.57 265.43) (xy 266.7 265.43)
		)
		(stroke
			(width 0)
			(type default)
		)
	)
	(polyline
		(pts
			(xy 201.93 161.29) (xy 297.18 161.29)
		)
		(stroke
			(width 0)
			(type dot)
		)
	)
	(wire
		(pts
			(xy 309.88 91.44) (xy 309.88 95.25)
		)
		(stroke
			(width 0)
			(type default)
		)
	)
	(wire
		(pts
			(xy 96.52 82.55) (xy 96.52 86.36)
		)
		(stroke
			(width 0)
			(type default)
		)
	)
	(wire
		(pts
			(xy 115.57 125.73) (xy 115.57 128.27)
		)
		(stroke
			(width 0)
			(type default)
		)
	)
	(wire
		(pts
			(xy 62.23 34.29) (xy 62.23 45.72)
		)
		(stroke
			(width 0)
			(type default)
		)
	)
	(wire
		(pts
			(xy 46.99 67.31) (xy 46.99 68.58)
		)
		(stroke
			(width 0)
			(type default)
		)
	)
	(wire
		(pts
			(xy 237.49 60.96) (xy 246.38 60.96)
		)
		(stroke
			(width 0)
			(type default)
		)
	)
	(wire
		(pts
			(xy 171.45 158.75) (xy 173.99 158.75)
		)
		(stroke
			(width 0)
			(type default)
		)
	)
	(wire
		(pts
			(xy 252.73 231.14) (xy 252.73 233.68)
		)
		(stroke
			(width 0)
			(type default)
		)
	)
	(wire
		(pts
			(xy 111.76 41.91) (xy 137.16 41.91)
		)
		(stroke
			(width 0)
			(type default)
		)
	)
	(wire
		(pts
			(xy 72.39 44.45) (xy 72.39 48.26)
		)
		(stroke
			(width 0)
			(type default)
		)
	)
	(wire
		(pts
			(xy 353.06 237.49) (xy 353.06 240.03)
		)
		(stroke
			(width 0)
			(type default)
		)
	)
	(wire
		(pts
			(xy 279.4 275.59) (xy 281.94 275.59)
		)
		(stroke
			(width 0)
			(type default)
		)
	)
	(polyline
		(pts
			(xy 406.4 109.22) (xy 209.55 109.22)
		)
		(stroke
			(width 0)
			(type default)
		)
	)
	(wire
		(pts
			(xy 331.47 91.44) (xy 360.68 91.44)
		)
		(stroke
			(width 0)
			(type default)
		)
	)
	(wire
		(pts
			(xy 21.59 67.31) (xy 21.59 69.85)
		)
		(stroke
			(width 0)
			(type default)
		)
	)
	(wire
		(pts
			(xy 236.22 63.5) (xy 240.03 63.5)
		)
		(stroke
			(width 0)
			(type default)
		)
	)
	(wire
		(pts
			(xy 248.92 58.42) (xy 248.92 66.04)
		)
		(stroke
			(width 0)
			(type default)
		)
	)
	(wire
		(pts
			(xy 252.73 248.92) (xy 252.73 250.19)
		)
		(stroke
			(width 0)
			(type default)
		)
	)
	(wire
		(pts
			(xy 379.73 91.44) (xy 377.19 91.44)
		)
		(stroke
			(width 0)
			(type default)
		)
	)
	(bus
		(pts
			(xy 240.03 257.81) (xy 238.76 257.81)
		)
		(stroke
			(width 0)
			(type default)
		)
	)
	(wire
		(pts
			(xy 115.57 143.51) (xy 115.57 146.05)
		)
		(stroke
			(width 0)
			(type default)
		)
	)
	(wire
		(pts
			(xy 58.42 214.63) (xy 58.42 212.09)
		)
		(stroke
			(width 0)
			(type default)
		)
	)
	(wire
		(pts
			(xy 67.31 44.45) (xy 67.31 45.72)
		)
		(stroke
			(width 0)
			(type default)
		)
	)
	(wire
		(pts
			(xy 55.88 176.53) (xy 58.42 176.53)
		)
		(stroke
			(width 0)
			(type default)
		)
	)
	(wire
		(pts
			(xy 382.27 96.52) (xy 382.27 99.06)
		)
		(stroke
			(width 0)
			(type default)
		)
	)
	(bus
		(pts
			(xy 369.57 59.69) (xy 369.57 62.23)
		)
		(stroke
			(width 0)
			(type default)
		)
	)
	(wire
		(pts
			(xy 345.44 185.42) (xy 368.3 185.42)
		)
		(stroke
			(width 0)
			(type default)
		)
	)
	(polyline
		(pts
			(xy 289.56 40.64) (xy 289.56 55.88)
		)
		(stroke
			(width 0)
			(type default)
		)
	)
	(wire
		(pts
			(xy 387.35 237.49) (xy 387.35 240.03)
		)
		(stroke
			(width 0)
			(type default)
		)
	)
	(wire
		(pts
			(xy 242.57 135.89) (xy 251.46 135.89)
		)
		(stroke
			(width 0)
			(type default)
		)
	)
	(wire
		(pts
			(xy 302.26 210.82) (xy 313.69 210.82)
		)
		(stroke
			(width 0)
			(type default)
		)
	)
	(wire
		(pts
			(xy 137.16 41.91) (xy 137.16 48.26)
		)
		(stroke
			(width 0)
			(type default)
		)
	)
	(wire
		(pts
			(xy 137.16 48.26) (xy 166.37 48.26)
		)
		(stroke
			(width 0)
			(type default)
		)
	)
	(wire
		(pts
			(xy 309.88 76.2) (xy 309.88 77.47)
		)
		(stroke
			(width 0)
			(type default)
		)
	)
	(wire
		(pts
			(xy 77.47 92.71) (xy 77.47 95.25)
		)
		(stroke
			(width 0)
			(type default)
		)
	)
	(wire
		(pts
			(xy 236.22 78.74) (xy 237.49 78.74)
		)
		(stroke
			(width 0)
			(type default)
		)
	)
	(wire
		(pts
			(xy 240.03 63.5) (xy 240.03 58.42)
		)
		(stroke
			(width 0)
			(type default)
		)
	)
	(wire
		(pts
			(xy 165.1 40.64) (xy 166.37 40.64)
		)
		(stroke
			(width 0)
			(type default)
		)
	)
	(wire
		(pts
			(xy 69.85 41.91) (xy 67.31 39.37)
		)
		(stroke
			(width 0)
			(type default)
		)
	)
	(wire
		(pts
			(xy 104.14 167.64) (xy 116.84 167.64)
		)
		(stroke
			(width 0)
			(type default)
		)
	)
	(wire
		(pts
			(xy 307.34 21.59) (xy 307.34 24.13)
		)
		(stroke
			(width 0)
			(type default)
		)
	)
	(wire
		(pts
			(xy 306.07 60.96) (xy 327.66 60.96)
		)
		(stroke
			(width 0)
			(type default)
		)
	)
	(wire
		(pts
			(xy 281.94 275.59) (xy 281.94 278.13)
		)
		(stroke
			(width 0)
			(type default)
		)
	)
	(polyline
		(pts
			(xy 201.93 161.29) (xy 201.93 127)
		)
		(stroke
			(width 0)
			(type dot)
		)
	)
	(bus
		(pts
			(xy 388.62 208.28) (xy 388.62 209.55)
		)
		(stroke
			(width 0)
			(type default)
		)
	)
	(wire
		(pts
			(xy 285.75 60.96) (xy 292.1 60.96)
		)
		(stroke
			(width 0)
			(type default)
		)
	)
	(bus
		(pts
			(xy 369.57 175.26) (xy 369.57 176.53)
		)
		(stroke
			(width 0)
			(type default)
		)
	)
	(wire
		(pts
			(xy 350.52 208.28) (xy 367.03 208.28)
		)
		(stroke
			(width 0)
			(type default)
		)
	)
	(wire
		(pts
			(xy 298.45 143.51) (xy 313.69 143.51)
		)
		(stroke
			(width 0)
			(type default)
		)
	)
	(wire
		(pts
			(xy 214.63 189.23) (xy 238.76 189.23)
		)
		(stroke
			(width 0)
			(type default)
		)
	)
	(wire
		(pts
			(xy 281.94 262.89) (xy 281.94 264.16)
		)
		(stroke
			(width 0)
			(type default)
		)
	)
	(wire
		(pts
			(xy 160.02 180.34) (xy 173.99 180.34)
		)
		(stroke
			(width 0)
			(type default)
		)
	)
	(wire
		(pts
			(xy 50.8 39.37) (xy 59.69 39.37)
		)
		(stroke
			(width 0)
			(type default)
		)
	)
	(wire
		(pts
			(xy 160.02 207.01) (xy 160.02 210.82)
		)
		(stroke
			(width 0)
			(type default)
		)
	)
	(wire
		(pts
			(xy 88.9 125.73) (xy 97.79 125.73)
		)
		(stroke
			(width 0)
			(type default)
		)
	)
	(wire
		(pts
			(xy 64.77 130.81) (xy 64.77 133.35)
		)
		(stroke
			(width 0)
			(type default)
		)
	)
	(polyline
		(pts
			(xy 274.32 63.5) (xy 300.99 63.5)
		)
		(stroke
			(width 0)
			(type dash)
		)
	)
	(bus
		(pts
			(xy 369.57 71.12) (xy 370.84 72.39)
		)
		(stroke
			(width 0)
			(type default)
		)
	)
	(wire
		(pts
			(xy 306.07 58.42) (xy 327.66 58.42)
		)
		(stroke
			(width 0)
			(type default)
		)
	)
	(wire
		(pts
			(xy 336.55 172.72) (xy 340.36 172.72)
		)
		(stroke
			(width 0)
			(type default)
		)
	)
	(wire
		(pts
			(xy 224.79 167.64) (xy 214.63 167.64)
		)
		(stroke
			(width 0)
			(type default)
		)
	)
	(wire
		(pts
			(xy 46.99 76.2) (xy 46.99 77.47)
		)
		(stroke
			(width 0)
			(type default)
		)
	)
	(wire
		(pts
			(xy 85.09 250.19) (xy 101.6 250.19)
		)
		(stroke
			(width 0)
			(type default)
		)
	)
	(wire
		(pts
			(xy 59.69 39.37) (xy 59.69 45.72)
		)
		(stroke
			(width 0)
			(type default)
		)
	)
	(wire
		(pts
			(xy 127 92.71) (xy 127 96.52)
		)
		(stroke
			(width 0)
			(type default)
		)
	)
	(wire
		(pts
			(xy 173.99 203.2) (xy 160.02 203.2)
		)
		(stroke
			(width 0)
			(type default)
		)
	)
	(bus
		(pts
			(xy 265.43 185.42) (xy 265.43 187.96)
		)
		(stroke
			(width 0)
			(type default)
		)
	)
	(wire
		(pts
			(xy 128.27 167.64) (xy 128.27 170.18)
		)
		(stroke
			(width 0)
			(type default)
		)
	)
	(wire
		(pts
			(xy 351.79 24.13) (xy 355.6 24.13)
		)
		(stroke
			(width 0)
			(type default)
		)
	)
	(wire
		(pts
			(xy 125.73 124.46) (xy 125.73 125.73)
		)
		(stroke
			(width 0)
			(type default)
		)
	)
	(wire
		(pts
			(xy 331.47 245.11) (xy 331.47 246.38)
		)
		(stroke
			(width 0)
			(type default)
		)
	)
	(wire
		(pts
			(xy 242.57 262.89) (xy 266.7 262.89)
		)
		(stroke
			(width 0)
			(type default)
		)
	)
	(wire
		(pts
			(xy 350.52 58.42) (xy 368.3 58.42)
		)
		(stroke
			(width 0)
			(type default)
		)
	)
	(wire
		(pts
			(xy 116.84 53.34) (xy 110.49 53.34)
		)
		(stroke
			(width 0)
			(type default)
		)
	)
	(wire
		(pts
			(xy 54.61 82.55) (xy 58.42 82.55)
		)
		(stroke
			(width 0)
			(type default)
		)
	)
	(wire
		(pts
			(xy 160.02 207.01) (xy 154.94 207.01)
		)
		(stroke
			(width 0)
			(type default)
		)
	)
	(wire
		(pts
			(xy 287.02 73.66) (xy 287.02 72.39)
		)
		(stroke
			(width 0)
			(type default)
		)
	)
	(wire
		(pts
			(xy 336.55 175.26) (xy 340.36 175.26)
		)
		(stroke
			(width 0)
			(type default)
		)
	)
	(wire
		(pts
			(xy 38.1 135.89) (xy 36.83 135.89)
		)
		(stroke
			(width 0)
			(type default)
		)
	)
	(wire
		(pts
			(xy 173.99 234.95) (xy 171.45 234.95)
		)
		(stroke
			(width 0)
			(type default)
		)
	)
	(wire
		(pts
			(xy 68.58 189.23) (xy 68.58 199.39)
		)
		(stroke
			(width 0)
			(type default)
		)
	)
	(wire
		(pts
			(xy 146.05 180.34) (xy 154.94 180.34)
		)
		(stroke
			(width 0)
			(type default)
		)
	)
	(bus
		(pts
			(xy 369.57 57.15) (xy 369.57 59.69)
		)
		(stroke
			(width 0)
			(type default)
		)
	)
	(wire
		(pts
			(xy 171.45 149.86) (xy 171.45 158.75)
		)
		(stroke
			(width 0)
			(type default)
		)
	)
	(wire
		(pts
			(xy 116.84 55.88) (xy 110.49 55.88)
		)
		(stroke
			(width 0)
			(type default)
		)
	)
	(wire
		(pts
			(xy 173.99 220.98) (xy 163.83 220.98)
		)
		(stroke
			(width 0)
			(type default)
		)
	)
	(wire
		(pts
			(xy 104.14 175.26) (xy 104.14 176.53)
		)
		(stroke
			(width 0)
			(type default)
		)
	)
	(wire
		(pts
			(xy 298.45 148.59) (xy 313.69 148.59)
		)
		(stroke
			(width 0)
			(type default)
		)
	)
	(wire
		(pts
			(xy 353.06 73.66) (xy 353.06 76.2)
		)
		(stroke
			(width 0)
			(type default)
		)
	)
	(wire
		(pts
			(xy 325.12 66.04) (xy 325.12 68.58)
		)
		(stroke
			(width 0)
			(type default)
		)
	)
	(wire
		(pts
			(xy 350.52 66.04) (xy 368.3 66.04)
		)
		(stroke
			(width 0)
			(type default)
		)
	)
	(wire
		(pts
			(xy 34.29 257.81) (xy 34.29 260.35)
		)
		(stroke
			(width 0)
			(type default)
		)
	)
	(polyline
		(pts
			(xy 215.9 205.74) (xy 261.62 205.74)
		)
		(stroke
			(width 0)
			(type default)
		)
	)
	(wire
		(pts
			(xy 121.92 250.19) (xy 135.89 250.19)
		)
		(stroke
			(width 0)
			(type default)
		)
	)
	(wire
		(pts
			(xy 360.68 101.6) (xy 360.68 100.33)
		)
		(stroke
			(width 0)
			(type default)
		)
	)
	(wire
		(pts
			(xy 123.19 234.95) (xy 130.81 234.95)
		)
		(stroke
			(width 0)
			(type default)
		)
	)
	(bus
		(pts
			(xy 241.3 259.08) (xy 240.03 257.81)
		)
		(stroke
			(width 0)
			(type default)
		)
	)
	(wire
		(pts
			(xy 166.37 83.82) (xy 165.1 83.82)
		)
		(stroke
			(width 0)
			(type default)
		)
	)
	(wire
		(pts
			(xy 125.73 125.73) (xy 125.73 128.27)
		)
		(stroke
			(width 0)
			(type default)
		)
	)
	(wire
		(pts
			(xy 236.22 58.42) (xy 240.03 58.42)
		)
		(stroke
			(width 0)
			(type default)
		)
	)
	(wire
		(pts
			(xy 73.66 245.11) (xy 73.66 238.76)
		)
		(stroke
			(width 0)
			(type default)
		)
	)
	(wire
		(pts
			(xy 331.47 180.34) (xy 340.36 180.34)
		)
		(stroke
			(width 0)
			(type default)
		)
	)
	(wire
		(pts
			(xy 21.59 96.52) (xy 44.45 96.52)
		)
		(stroke
			(width 0)
			(type default)
		)
	)
	(wire
		(pts
			(xy 85.09 245.11) (xy 101.6 245.11)
		)
		(stroke
			(width 0)
			(type default)
		)
	)
	(wire
		(pts
			(xy 252.73 233.68) (xy 265.43 233.68)
		)
		(stroke
			(width 0)
			(type default)
		)
	)
	(wire
		(pts
			(xy 130.81 234.95) (xy 130.81 229.87)
		)
		(stroke
			(width 0)
			(type default)
		)
	)
	(wire
		(pts
			(xy 312.42 50.8) (xy 327.66 50.8)
		)
		(stroke
			(width 0)
			(type default)
		)
	)
	(wire
		(pts
			(xy 331.47 151.13) (xy 341.63 151.13)
		)
		(stroke
			(width 0)
			(type default)
		)
	)
	(polyline
		(pts
			(xy 285.75 252.73) (xy 285.75 231.14)
		)
		(stroke
			(width 0)
			(type default)
		)
	)
	(bus
		(pts
			(xy 369.57 54.61) (xy 369.57 57.15)
		)
		(stroke
			(width 0)
			(type default)
		)
	)
	(wire
		(pts
			(xy 154.94 166.37) (xy 173.99 166.37)
		)
		(stroke
			(width 0)
			(type default)
		)
	)
	(wire
		(pts
			(xy 72.39 44.45) (xy 67.31 44.45)
		)
		(stroke
			(width 0)
			(type default)
		)
	)
	(wire
		(pts
			(xy 104.14 143.51) (xy 104.14 146.05)
		)
		(stroke
			(width 0)
			(type default)
		)
	)
	(wire
		(pts
			(xy 312.42 220.98) (xy 312.42 222.25)
		)
		(stroke
			(width 0)
			(type default)
		)
	)
	(wire
		(pts
			(xy 163.83 236.22) (xy 163.83 237.49)
		)
		(stroke
			(width 0)
			(type default)
		)
	)
	(wire
		(pts
			(xy 130.81 229.87) (xy 137.16 229.87)
		)
		(stroke
			(width 0)
			(type default)
		)
	)
	(wire
		(pts
			(xy 375.92 245.11) (xy 375.92 246.38)
		)
		(stroke
			(width 0)
			(type default)
		)
	)
	(wire
		(pts
			(xy 252.73 223.52) (xy 252.73 226.06)
		)
		(stroke
			(width 0)
			(type default)
		)
	)
	(wire
		(pts
			(xy 224.79 170.18) (xy 214.63 170.18)
		)
		(stroke
			(width 0)
			(type default)
		)
	)
	(wire
		(pts
			(xy 377.19 199.39) (xy 379.73 199.39)
		)
		(stroke
			(width 0)
			(type default)
		)
	)
	(wire
		(pts
			(xy 382.27 88.9) (xy 382.27 91.44)
		)
		(stroke
			(width 0)
			(type default)
		)
	)
	(wire
		(pts
			(xy 147.32 151.13) (xy 147.32 153.67)
		)
		(stroke
			(width 0)
			(type default)
		)
	)
	(wire
		(pts
			(xy 125.73 133.35) (xy 125.73 134.62)
		)
		(stroke
			(width 0)
			(type default)
		)
	)
	(wire
		(pts
			(xy 292.1 50.8) (xy 292.1 60.96)
		)
		(stroke
			(width 0)
			(type default)
		)
	)
	(wire
		(pts
			(xy 151.13 212.09) (xy 151.13 218.44)
		)
		(stroke
			(width 0)
			(type default)
		)
	)
	(wire
		(pts
			(xy 58.42 209.55) (xy 55.88 209.55)
		)
		(stroke
			(width 0)
			(type default)
		)
	)
	(wire
		(pts
			(xy 350.52 48.26) (xy 368.3 48.26)
		)
		(stroke
			(width 0)
			(type default)
		)
	)
	(wire
		(pts
			(xy 276.86 48.26) (xy 284.48 48.26)
		)
		(stroke
			(width 0)
			(type default)
		)
	)
	(wire
		(pts
			(xy 146.05 229.87) (xy 137.16 229.87)
		)
		(stroke
			(width 0)
			(type default)
		)
	)
	(wire
		(pts
			(xy 236.22 55.88) (xy 237.49 55.88)
		)
		(stroke
			(width 0)
			(type default)
		)
	)
	(wire
		(pts
			(xy 173.99 149.86) (xy 171.45 149.86)
		)
		(stroke
			(width 0)
			(type default)
		)
	)
	(wire
		(pts
			(xy 341.63 237.49) (xy 353.06 237.49)
		)
		(stroke
			(width 0)
			(type default)
		)
	)
	(wire
		(pts
			(xy 77.47 95.25) (xy 77.47 97.79)
		)
		(stroke
			(width 0)
			(type default)
		)
	)
	(wire
		(pts
			(xy 81.28 198.12) (xy 81.28 203.2)
		)
		(stroke
			(width 0)
			(type default)
		)
	)
	(wire
		(pts
			(xy 281.94 278.13) (xy 281.94 279.4)
		)
		(stroke
			(width 0)
			(type default)
		)
	)
	(polyline
		(pts
			(xy 215.9 205.74) (xy 215.9 215.9)
		)
		(stroke
			(width 0)
			(type default)
		)
	)
	(wire
		(pts
			(xy 57.15 87.63) (xy 33.02 87.63)
		)
		(stroke
			(width 0)
			(type default)
		)
	)
	(wire
		(pts
			(xy 237.49 78.74) (xy 237.49 76.2)
		)
		(stroke
			(width 0)
			(type default)
		)
	)
	(wire
		(pts
			(xy 50.8 34.29) (xy 62.23 34.29)
		)
		(stroke
			(width 0)
			(type default)
		)
	)
	(wire
		(pts
			(xy 140.97 198.12) (xy 173.99 198.12)
		)
		(stroke
			(width 0)
			(type default)
		)
	)
	(wire
		(pts
			(xy 350.52 63.5) (xy 368.3 63.5)
		)
		(stroke
			(width 0)
			(type default)
		)
	)
	(wire
		(pts
			(xy 318.77 24.13) (xy 326.39 24.13)
		)
		(stroke
			(width 0)
			(type default)
		)
	)
	(wire
		(pts
			(xy 57.15 87.63) (xy 57.15 91.44)
		)
		(stroke
			(width 0)
			(type default)
		)
	)
	(wire
		(pts
			(xy 397.51 245.11) (xy 397.51 246.38)
		)
		(stroke
			(width 0)
			(type default)
		)
	)
	(polyline
		(pts
			(xy 215.9 184.15) (xy 215.9 194.31)
		)
		(stroke
			(width 0)
			(type default)
		)
	)
	(wire
		(pts
			(xy 292.1 60.96) (xy 300.99 60.96)
		)
		(stroke
			(width 0)
			(type default)
		)
	)
	(bus
		(pts
			(xy 369.57 176.53) (xy 369.57 179.07)
		)
		(stroke
			(width 0)
			(type default)
		)
	)
	(wire
		(pts
			(xy 21.59 78.74) (xy 21.59 85.09)
		)
		(stroke
			(width 0)
			(type default)
		)
	)
	(wire
		(pts
			(xy 350.52 60.96) (xy 368.3 60.96)
		)
		(stroke
			(width 0)
			(type default)
		)
	)
	(wire
		(pts
			(xy 379.73 217.17) (xy 387.35 217.17)
		)
		(stroke
			(width 0)
			(type default)
		)
	)
	(wire
		(pts
			(xy 66.04 181.61) (xy 66.04 199.39)
		)
		(stroke
			(width 0)
			(type default)
		)
	)
	(wire
		(pts
			(xy 350.52 53.34) (xy 368.3 53.34)
		)
		(stroke
			(width 0)
			(type default)
		)
	)
	(wire
		(pts
			(xy 72.39 247.65) (xy 80.01 247.65)
		)
		(stroke
			(width 0)
			(type default)
		)
	)
	(bus
		(pts
			(xy 265.43 205.74) (xy 266.7 204.47)
		)
		(stroke
			(width 0)
			(type default)
		)
	)
	(wire
		(pts
			(xy 73.66 184.15) (xy 73.66 199.39)
		)
		(stroke
			(width 0)
			(type default)
		)
	)
	(wire
		(pts
			(xy 251.46 146.05) (xy 252.73 146.05)
		)
		(stroke
			(width 0)
			(type default)
		)
	)
	(wire
		(pts
			(xy 359.41 86.36) (xy 361.95 86.36)
		)
		(stroke
			(width 0)
			(type default)
		)
	)
	(wire
		(pts
			(xy 309.88 102.87) (xy 309.88 100.33)
		)
		(stroke
			(width 0)
			(type default)
		)
	)
	(wire
		(pts
			(xy 345.44 177.8) (xy 368.3 177.8)
		)
		(stroke
			(width 0)
			(type default)
		)
	)
	(bus
		(pts
			(xy 147.32 62.23) (xy 147.32 64.77)
		)
		(stroke
			(width 0)
			(type default)
		)
	)
	(wire
		(pts
			(xy 73.66 85.09) (xy 77.47 85.09)
		)
		(stroke
			(width 0)
			(type default)
		)
	)
	(wire
		(pts
			(xy 148.59 55.88) (xy 166.37 55.88)
		)
		(stroke
			(width 0)
			(type default)
		)
	)
	(wire
		(pts
			(xy 298.45 146.05) (xy 313.69 146.05)
		)
		(stroke
			(width 0)
			(type default)
		)
	)
	(wire
		(pts
			(xy 279.4 270.51) (xy 294.64 270.51)
		)
		(stroke
			(width 0)
			(type default)
		)
	)
	(wire
		(pts
			(xy 71.12 191.77) (xy 71.12 199.39)
		)
		(stroke
			(width 0)
			(type default)
		)
	)
	(wire
		(pts
			(xy 55.88 194.31) (xy 57.15 194.31)
		)
		(stroke
			(width 0)
			(type default)
		)
	)
	(wire
		(pts
			(xy 341.63 237.49) (xy 341.63 240.03)
		)
		(stroke
			(width 0)
			(type default)
		)
	)
	(wire
		(pts
			(xy 110.49 52.07) (xy 110.49 53.34)
		)
		(stroke
			(width 0)
			(type default)
		)
	)
	(wire
		(pts
			(xy 125.73 151.13) (xy 125.73 153.67)
		)
		(stroke
			(width 0)
			(type default)
		)
	)
	(wire
		(pts
			(xy 33.02 87.63) (xy 33.02 78.74)
		)
		(stroke
			(width 0)
			(type default)
		)
	)
	(wire
		(pts
			(xy 58.42 251.46) (xy 72.39 251.46)
		)
		(stroke
			(width 0)
			(type default)
		)
	)
	(polyline
		(pts
			(xy 289.56 55.88) (xy 313.69 55.88)
		)
		(stroke
			(width 0)
			(type default)
		)
	)
	(wire
		(pts
			(xy 252.73 233.68) (xy 252.73 236.22)
		)
		(stroke
			(width 0)
			(type default)
		)
	)
	(wire
		(pts
			(xy 360.68 91.44) (xy 361.95 91.44)
		)
		(stroke
			(width 0)
			(type default)
		)
	)
	(wire
		(pts
			(xy 331.47 96.52) (xy 337.82 96.52)
		)
		(stroke
			(width 0)
			(type default)
		)
	)
	(wire
		(pts
			(xy 74.93 87.63) (xy 74.93 95.25)
		)
		(stroke
			(width 0)
			(type default)
		)
	)
	(wire
		(pts
			(xy 364.49 217.17) (xy 379.73 217.17)
		)
		(stroke
			(width 0)
			(type default)
		)
	)
	(wire
		(pts
			(xy 334.01 172.72) (xy 331.47 172.72)
		)
		(stroke
			(width 0)
			(type default)
		)
	)
	(wire
		(pts
			(xy 140.97 198.12) (xy 140.97 207.01)
		)
		(stroke
			(width 0)
			(type default)
		)
	)
	(wire
		(pts
			(xy 58.42 135.89) (xy 59.69 135.89)
		)
		(stroke
			(width 0)
			(type default)
		)
	)
	(wire
		(pts
			(xy 325.12 66.04) (xy 327.66 66.04)
		)
		(stroke
			(width 0)
			(type default)
		)
	)
	(wire
		(pts
			(xy 284.48 48.26) (xy 284.48 50.8)
		)
		(stroke
			(width 0)
			(type default)
		)
	)
	(wire
		(pts
			(xy 377.19 86.36) (xy 392.43 86.36)
		)
		(stroke
			(width 0)
			(type default)
		)
	)
	(wire
		(pts
			(xy 312.42 187.96) (xy 312.42 189.23)
		)
		(stroke
			(width 0)
			(type default)
		)
	)
	(wire
		(pts
			(xy 237.49 76.2) (xy 236.22 76.2)
		)
		(stroke
			(width 0)
			(type default)
		)
	)
	(wire
		(pts
			(xy 214.63 148.59) (xy 229.87 148.59)
		)
		(stroke
			(width 0)
			(type default)
		)
	)
	(wire
		(pts
			(xy 165.1 38.1) (xy 166.37 38.1)
		)
		(stroke
			(width 0)
			(type default)
		)
	)
	(wire
		(pts
			(xy 140.97 207.01) (xy 140.97 210.82)
		)
		(stroke
			(width 0)
			(type default)
		)
	)
	(wire
		(pts
			(xy 73.66 245.11) (xy 80.01 245.11)
		)
		(stroke
			(width 0)
			(type default)
		)
	)
	(bus
		(pts
			(xy 142.24 71.12) (xy 147.32 71.12)
		)
		(stroke
			(width 0)
			(type default)
		)
	)
	(polyline
		(pts
			(xy 215.9 215.9) (xy 261.62 215.9)
		)
		(stroke
			(width 0)
			(type default)
		)
	)
	(wire
		(pts
			(xy 242.57 223.52) (xy 252.73 223.52)
		)
		(stroke
			(width 0)
			(type default)
		)
	)
	(wire
		(pts
			(xy 106.68 85.09) (xy 106.68 87.63)
		)
		(stroke
			(width 0)
			(type default)
		)
	)
	(wire
		(pts
			(xy 58.42 196.85) (xy 58.42 191.77)
		)
		(stroke
			(width 0)
			(type default)
		)
	)
	(wire
		(pts
			(xy 400.05 83.82) (xy 400.05 86.36)
		)
		(stroke
			(width 0)
			(type default)
		)
	)
	(bus
		(pts
			(xy 369.57 181.61) (xy 369.57 184.15)
		)
		(stroke
			(width 0)
			(type default)
		)
	)
	(wire
		(pts
			(xy 312.42 213.36) (xy 312.42 220.98)
		)
		(stroke
			(width 0)
			(type default)
		)
	)
	(wire
		(pts
			(xy 355.6 31.75) (xy 355.6 33.02)
		)
		(stroke
			(width 0)
			(type default)
		)
	)
	(bus
		(pts
			(xy 265.43 184.15) (xy 266.7 182.88)
		)
		(stroke
			(width 0)
			(type default)
		)
	)
	(wire
		(pts
			(xy 285.75 60.96) (xy 285.75 64.77)
		)
		(stroke
			(width 0)
			(type default)
		)
	)
	(wire
		(pts
			(xy 300.99 177.8) (xy 313.69 177.8)
		)
		(stroke
			(width 0)
			(type default)
		)
	)
	(wire
		(pts
			(xy 331.47 237.49) (xy 341.63 237.49)
		)
		(stroke
			(width 0)
			(type default)
		)
	)
	(bus
		(pts
			(xy 93.98 153.67) (xy 91.44 153.67)
		)
		(stroke
			(width 0)
			(type default)
		)
	)
	(wire
		(pts
			(xy 173.99 124.46) (xy 173.99 125.73)
		)
		(stroke
			(width 0)
			(type default)
		)
	)
	(wire
		(pts
			(xy 306.07 50.8) (xy 312.42 50.8)
		)
		(stroke
			(width 0)
			(type default)
		)
	)
	(bus
		(pts
			(xy 147.32 57.15) (xy 147.32 59.69)
		)
		(stroke
			(width 0)
			(type default)
		)
	)
	(wire
		(pts
			(xy 350.52 45.72) (xy 368.3 45.72)
		)
		(stroke
			(width 0)
			(type default)
		)
	)
	(wire
		(pts
			(xy 73.66 82.55) (xy 88.9 82.55)
		)
		(stroke
			(width 0)
			(type default)
		)
	)
	(wire
		(pts
			(xy 246.38 60.96) (xy 246.38 66.04)
		)
		(stroke
			(width 0)
			(type default)
		)
	)
	(wire
		(pts
			(xy 331.47 74.93) (xy 331.47 76.2)
		)
		(stroke
			(width 0)
			(type default)
		)
	)
	(polyline
		(pts
			(xy 313.69 40.64) (xy 289.56 40.64)
		)
		(stroke
			(width 0)
			(type default)
		)
	)
	(wire
		(pts
			(xy 57.15 96.52) (xy 57.15 99.06)
		)
		(stroke
			(width 0)
			(type default)
		)
	)
	(wire
		(pts
			(xy 64.77 143.51) (xy 64.77 140.97)
		)
		(stroke
			(width 0)
			(type default)
		)
	)
	(wire
		(pts
			(xy 316.23 100.33) (xy 321.31 100.33)
		)
		(stroke
			(width 0)
			(type default)
		)
	)
	(wire
		(pts
			(xy 148.59 68.58) (xy 166.37 68.58)
		)
		(stroke
			(width 0)
			(type default)
		)
	)
	(bus
		(pts
			(xy 369.57 52.07) (xy 369.57 54.61)
		)
		(stroke
			(width 0)
			(type default)
		)
	)
	(wire
		(pts
			(xy 392.43 86.36) (xy 400.05 86.36)
		)
		(stroke
			(width 0)
			(type default)
		)
	)
	(wire
		(pts
			(xy 269.24 140.97) (xy 270.51 140.97)
		)
		(stroke
			(width 0)
			(type default)
		)
	)
	(wire
		(pts
			(xy 240.03 58.42) (xy 248.92 58.42)
		)
		(stroke
			(width 0)
			(type default)
		)
	)
	(wire
		(pts
			(xy 171.45 234.95) (xy 171.45 237.49)
		)
		(stroke
			(width 0)
			(type default)
		)
	)
	(wire
		(pts
			(xy 21.59 90.17) (xy 21.59 96.52)
		)
		(stroke
			(width 0)
			(type default)
		)
	)
	(wire
		(pts
			(xy 350.52 55.88) (xy 368.3 55.88)
		)
		(stroke
			(width 0)
			(type default)
		)
	)
	(wire
		(pts
			(xy 392.43 86.36) (xy 392.43 91.44)
		)
		(stroke
			(width 0)
			(type default)
		)
	)
	(wire
		(pts
			(xy 318.77 24.13) (xy 318.77 26.67)
		)
		(stroke
			(width 0)
			(type default)
		)
	)
	(wire
		(pts
			(xy 314.96 237.49) (xy 321.31 237.49)
		)
		(stroke
			(width 0)
			(type default)
		)
	)
	(wire
		(pts
			(xy 365.76 237.49) (xy 375.92 237.49)
		)
		(stroke
			(width 0)
			(type default)
		)
	)
	(wire
		(pts
			(xy 125.73 143.51) (xy 125.73 146.05)
		)
		(stroke
			(width 0)
			(type default)
		)
	)
	(wire
		(pts
			(xy 59.69 135.89) (xy 59.69 143.51)
		)
		(stroke
			(width 0)
			(type default)
		)
	)
	(wire
		(pts
			(xy 321.31 237.49) (xy 331.47 237.49)
		)
		(stroke
			(width 0)
			(type default)
		)
	)
	(wire
		(pts
			(xy 72.39 247.65) (xy 72.39 245.11)
		)
		(stroke
			(width 0)
			(type default)
		)
	)
	(wire
		(pts
			(xy 55.88 189.23) (xy 57.15 189.23)
		)
		(stroke
			(width 0)
			(type default)
		)
	)
	(wire
		(pts
			(xy 337.82 138.43) (xy 341.63 138.43)
		)
		(stroke
			(width 0)
			(type default)
		)
	)
	(wire
		(pts
			(xy 350.52 205.74) (xy 367.03 205.74)
		)
		(stroke
			(width 0)
			(type default)
		)
	)
	(wire
		(pts
			(xy 72.39 250.19) (xy 80.01 250.19)
		)
		(stroke
			(width 0)
			(type default)
		)
	)
	(wire
		(pts
			(xy 370.84 48.26) (xy 392.43 48.26)
		)
		(stroke
			(width 0)
			(type default)
		)
	)
	(wire
		(pts
			(xy 85.09 247.65) (xy 101.6 247.65)
		)
		(stroke
			(width 0)
			(type default)
		)
	)
	(wire
		(pts
			(xy 77.47 85.09) (xy 77.47 87.63)
		)
		(stroke
			(width 0)
			(type default)
		)
	)
	(bus
		(pts
			(xy 369.57 175.26) (xy 370.84 172.72)
		)
		(stroke
			(width 0)
			(type default)
		)
	)
	(wire
		(pts
			(xy 312.42 153.67) (xy 313.69 153.67)
		)
		(stroke
			(width 0)
			(type default)
		)
	)
	(bus
		(pts
			(xy 373.38 138.43) (xy 370.84 138.43)
		)
		(stroke
			(width 0)
			(type default)
		)
	)
	(wire
		(pts
			(xy 300.99 182.88) (xy 313.69 182.88)
		)
		(stroke
			(width 0)
			(type default)
		)
	)
	(wire
		(pts
			(xy 331.47 140.97) (xy 350.52 140.97)
		)
		(stroke
			(width 0)
			(type default)
		)
	)
	(wire
		(pts
			(xy 351.79 24.13) (xy 351.79 40.64)
		)
		(stroke
			(width 0)
			(type default)
		)
	)
	(wire
		(pts
			(xy 288.29 69.85) (xy 288.29 72.39)
		)
		(stroke
			(width 0)
			(type default)
		)
	)
	(wire
		(pts
			(xy 355.6 218.44) (xy 355.6 217.17)
		)
		(stroke
			(width 0)
			(type default)
		)
	)
	(wire
		(pts
			(xy 148.59 60.96) (xy 166.37 60.96)
		)
		(stroke
			(width 0)
			(type default)
		)
	)
	(wire
		(pts
			(xy 160.02 203.2) (xy 160.02 207.01)
		)
		(stroke
			(width 0)
			(type default)
		)
	)
	(wire
		(pts
			(xy 302.26 215.9) (xy 313.69 215.9)
		)
		(stroke
			(width 0)
			(type default)
		)
	)
	(wire
		(pts
			(xy 146.05 232.41) (xy 146.05 229.87)
		)
		(stroke
			(width 0)
			(type default)
		)
	)
	(bus
		(pts
			(xy 147.32 67.31) (xy 147.32 69.85)
		)
		(stroke
			(width 0)
			(type default)
		)
	)
	(wire
		(pts
			(xy 243.84 48.26) (xy 243.84 66.04)
		)
		(stroke
			(width 0)
			(type default)
		)
	)
	(wire
		(pts
			(xy 46.99 68.58) (xy 54.61 68.58)
		)
		(stroke
			(width 0)
			(type default)
		)
	)
	(polyline
		(pts
			(xy 201.93 162.56) (xy 201.93 179.07)
		)
		(stroke
			(width 0)
			(type dot)
		)
	)
	(wire
		(pts
			(xy 123.19 255.27) (xy 123.19 256.54)
		)
		(stroke
			(width 0)
			(type default)
		)
	)
	(wire
		(pts
			(xy 353.06 245.11) (xy 353.06 246.38)
		)
		(stroke
			(width 0)
			(type default)
		)
	)
	(wire
		(pts
			(xy 88.9 82.55) (xy 96.52 82.55)
		)
		(stroke
			(width 0)
			(type default)
		)
	)
	(wire
		(pts
			(xy 243.84 208.28) (xy 264.16 208.28)
		)
		(stroke
			(width 0)
			(type default)
		)
	)
	(wire
		(pts
			(xy 127 85.09) (xy 139.7 85.09)
		)
		(stroke
			(width 0)
			(type default)
		)
	)
	(wire
		(pts
			(xy 331.47 237.49) (xy 331.47 240.03)
		)
		(stroke
			(width 0)
			(type default)
		)
	)
	(wire
		(pts
			(xy 331.47 185.42) (xy 340.36 185.42)
		)
		(stroke
			(width 0)
			(type default)
		)
	)
	(wire
		(pts
			(xy 364.49 210.82) (xy 377.19 210.82)
		)
		(stroke
			(width 0)
			(type default)
		)
	)
	(wire
		(pts
			(xy 288.29 58.42) (xy 294.64 58.42)
		)
		(stroke
			(width 0)
			(type default)
		)
	)
	(bus
		(pts
			(xy 369.57 142.24) (xy 369.57 144.78)
		)
		(stroke
			(width 0)
			(type default)
		)
	)
	(bus
		(pts
			(xy 369.57 144.78) (xy 369.57 147.32)
		)
		(stroke
			(width 0)
			(type default)
		)
	)
	(polyline
		(pts
			(xy 201.93 127) (xy 297.18 127)
		)
		(stroke
			(width 0)
			(type dot)
		)
	)
	(wire
		(pts
			(xy 161.29 190.5) (xy 173.99 190.5)
		)
		(stroke
			(width 0)
			(type default)
		)
	)
	(wire
		(pts
			(xy 95.25 143.51) (xy 104.14 143.51)
		)
		(stroke
			(width 0)
			(type default)
		)
	)
	(wire
		(pts
			(xy 73.66 252.73) (xy 80.01 252.73)
		)
		(stroke
			(width 0)
			(type default)
		)
	)
	(wire
		(pts
			(xy 392.43 45.72) (xy 370.84 45.72)
		)
		(stroke
			(width 0)
			(type default)
		)
	)
	(bus
		(pts
			(xy 388.62 208.28) (xy 389.89 208.28)
		)
		(stroke
			(width 0)
			(type default)
		)
	)
	(wire
		(pts
			(xy 300.99 53.34) (xy 294.64 53.34)
		)
		(stroke
			(width 0)
			(type default)
		)
	)
	(wire
		(pts
			(xy 148.59 63.5) (xy 166.37 63.5)
		)
		(stroke
			(width 0)
			(type default)
		)
	)
	(polyline
		(pts
			(xy 393.7 185.42) (xy 393.7 198.12)
		)
		(stroke
			(width 0)
			(type default)
		)
	)
	(wire
		(pts
			(xy 34.29 238.76) (xy 34.29 245.11)
		)
		(stroke
			(width 0)
			(type default)
		)
	)
	(wire
		(pts
			(xy 35.56 67.31) (xy 35.56 71.12)
		)
		(stroke
			(width 0)
			(type default)
		)
	)
	(wire
		(pts
			(xy 30.48 143.51) (xy 30.48 140.97)
		)
		(stroke
			(width 0)
			(type default)
		)
	)
	(wire
		(pts
			(xy 300.99 180.34) (xy 313.69 180.34)
		)
		(stroke
			(width 0)
			(type default)
		)
	)
	(wire
		(pts
			(xy 254 66.04) (xy 254 64.77)
		)
		(stroke
			(width 0)
			(type default)
		)
	)
	(wire
		(pts
			(xy 137.16 143.51) (xy 147.32 143.51)
		)
		(stroke
			(width 0)
			(type default)
		)
	)
	(wire
		(pts
			(xy 121.92 53.34) (xy 146.05 53.34)
		)
		(stroke
			(width 0)
			(type default)
		)
	)
	(polyline
		(pts
			(xy 215.9 184.15) (xy 261.62 184.15)
		)
		(stroke
			(width 0)
			(type default)
		)
	)
	(wire
		(pts
			(xy 171.45 232.41) (xy 171.45 234.95)
		)
		(stroke
			(width 0)
			(type default)
		)
	)
	(polyline
		(pts
			(xy 285.75 228.6) (xy 407.67 228.6)
		)
		(stroke
			(width 0)
			(type dot)
		)
	)
	(wire
		(pts
			(xy 287.02 72.39) (xy 285.75 72.39)
		)
		(stroke
			(width 0)
			(type default)
		)
	)
	(wire
		(pts
			(xy 345.44 175.26) (xy 368.3 175.26)
		)
		(stroke
			(width 0)
			(type default)
		)
	)
	(bus
		(pts
			(xy 281.94 143.51) (xy 283.21 143.51)
		)
		(stroke
			(width 0)
			(type default)
		)
	)
	(wire
		(pts
			(xy 21.59 74.93) (xy 21.59 78.74)
		)
		(stroke
			(width 0)
			(type default)
		)
	)
	(wire
		(pts
			(xy 162.56 125.73) (xy 162.56 128.27)
		)
		(stroke
			(width 0)
			(type default)
		)
	)
	(wire
		(pts
			(xy 161.29 187.96) (xy 173.99 187.96)
		)
		(stroke
			(width 0)
			(type default)
		)
	)
	(wire
		(pts
			(xy 285.75 69.85) (xy 285.75 72.39)
		)
		(stroke
			(width 0)
			(type default)
		)
	)
	(polyline
		(pts
			(xy 300.99 63.5) (xy 300.99 81.28)
		)
		(stroke
			(width 0)
			(type dash)
		)
	)
	(polyline
		(pts
			(xy 285.75 231.14) (xy 407.67 231.14)
		)
		(stroke
			(width 0)
			(type dash)
		)
	)
	(wire
		(pts
			(xy 55.88 196.85) (xy 58.42 196.85)
		)
		(stroke
			(width 0)
			(type default)
		)
	)
	(wire
		(pts
			(xy 57.15 87.63) (xy 58.42 87.63)
		)
		(stroke
			(width 0)
			(type default)
		)
	)
	(wire
		(pts
			(xy 379.73 99.06) (xy 382.27 99.06)
		)
		(stroke
			(width 0)
			(type default)
		)
	)
	(bus
		(pts
			(xy 265.43 184.15) (xy 265.43 185.42)
		)
		(stroke
			(width 0)
			(type default)
		)
	)
	(wire
		(pts
			(xy 76.2 198.12) (xy 81.28 198.12)
		)
		(stroke
			(width 0)
			(type default)
		)
	)
	(polyline
		(pts
			(xy 393.7 185.42) (xy 374.65 185.42)
		)
		(stroke
			(width 0)
			(type default)
		)
	)
	(wire
		(pts
			(xy 36.83 133.35) (xy 36.83 135.89)
		)
		(stroke
			(width 0)
			(type default)
		)
	)
	(wire
		(pts
			(xy 251.46 50.8) (xy 271.78 50.8)
		)
		(stroke
			(width 0)
			(type default)
		)
	)
	(wire
		(pts
			(xy 173.99 133.35) (xy 173.99 134.62)
		)
		(stroke
			(width 0)
			(type default)
		)
	)
	(wire
		(pts
			(xy 148.59 53.34) (xy 166.37 53.34)
		)
		(stroke
			(width 0)
			(type default)
		)
	)
	(wire
		(pts
			(xy 173.99 146.05) (xy 171.45 146.05)
		)
		(stroke
			(width 0)
			(type default)
		)
	)
	(wire
		(pts
			(xy 355.6 22.86) (xy 355.6 24.13)
		)
		(stroke
			(width 0)
			(type default)
		)
	)
	(wire
		(pts
			(xy 30.48 133.35) (xy 36.83 133.35)
		)
		(stroke
			(width 0)
			(type default)
		)
	)
	(wire
		(pts
			(xy 400.05 86.36) (xy 400.05 91.44)
		)
		(stroke
			(width 0)
			(type default)
		)
	)
	(wire
		(pts
			(xy 397.51 45.72) (xy 405.13 45.72)
		)
		(stroke
			(width 0)
			(type default)
		)
	)
	(wire
		(pts
			(xy 246.38 60.96) (xy 285.75 60.96)
		)
		(stroke
			(width 0)
			(type default)
		)
	)
	(wire
		(pts
			(xy 331.47 215.9) (xy 346.71 215.9)
		)
		(stroke
			(width 0)
			(type default)
		)
	)
	(wire
		(pts
			(xy 139.7 45.72) (xy 139.7 39.37)
		)
		(stroke
			(width 0)
			(type default)
		)
	)
	(wire
		(pts
			(xy 35.56 76.2) (xy 35.56 85.09)
		)
		(stroke
			(width 0)
			(type default)
		)
	)
	(wire
		(pts
			(xy 147.32 143.51) (xy 147.32 146.05)
		)
		(stroke
			(width 0)
			(type default)
		)
	)
	(wire
		(pts
			(xy 345.44 182.88) (xy 368.3 182.88)
		)
		(stroke
			(width 0)
			(type default)
		)
	)
	(wire
		(pts
			(xy 346.71 138.43) (xy 350.52 138.43)
		)
		(stroke
			(width 0)
			(type default)
		)
	)
	(wire
		(pts
			(xy 64.77 133.35) (xy 80.01 133.35)
		)
		(stroke
			(width 0)
			(type default)
		)
	)
	(wire
		(pts
			(xy 331.47 91.44) (xy 331.47 96.52)
		)
		(stroke
			(width 0)
			(type default)
		)
	)
	(bus
		(pts
			(xy 241.3 259.08) (xy 241.3 261.62)
		)
		(stroke
			(width 0)
			(type default)
		)
	)
	(wire
		(pts
			(xy 214.63 186.69) (xy 238.76 186.69)
		)
		(stroke
			(width 0)
			(type default)
		)
	)
	(wire
		(pts
			(xy 347.98 96.52) (xy 347.98 100.33)
		)
		(stroke
			(width 0)
			(type default)
		)
	)
	(polyline
		(pts
			(xy 261.62 194.31) (xy 261.62 184.15)
		)
		(stroke
			(width 0)
			(type default)
		)
	)
	(wire
		(pts
			(xy 377.19 88.9) (xy 382.27 88.9)
		)
		(stroke
			(width 0)
			(type default)
		)
	)
	(wire
		(pts
			(xy 214.63 208.28) (xy 238.76 208.28)
		)
		(stroke
			(width 0)
			(type default)
		)
	)
	(wire
		(pts
			(xy 171.45 146.05) (xy 171.45 143.51)
		)
		(stroke
			(width 0)
			(type default)
		)
	)
	(wire
		(pts
			(xy 104.14 143.51) (xy 115.57 143.51)
		)
		(stroke
			(width 0)
			(type default)
		)
	)
	(wire
		(pts
			(xy 36.83 133.35) (xy 38.1 133.35)
		)
		(stroke
			(width 0)
			(type default)
		)
	)
	(wire
		(pts
			(xy 116.84 167.64) (xy 128.27 167.64)
		)
		(stroke
			(width 0)
			(type default)
		)
	)
	(wire
		(pts
			(xy 269.24 146.05) (xy 270.51 146.05)
		)
		(stroke
			(width 0)
			(type default)
		)
	)
	(wire
		(pts
			(xy 337.82 134.62) (xy 337.82 138.43)
		)
		(stroke
			(width 0)
			(type default)
		)
	)
	(wire
		(pts
			(xy 365.76 245.11) (xy 365.76 246.38)
		)
		(stroke
			(width 0)
			(type default)
		)
	)
	(wire
		(pts
			(xy 302.26 218.44) (xy 313.69 218.44)
		)
		(stroke
			(width 0)
			(type default)
		)
	)
	(wire
		(pts
			(xy 288.29 58.42) (xy 288.29 64.77)
		)
		(stroke
			(width 0)
			(type default)
		)
	)
	(wire
		(pts
			(xy 355.6 217.17) (xy 355.6 215.9)
		)
		(stroke
			(width 0)
			(type default)
		)
	)
	(wire
		(pts
			(xy 154.94 153.67) (xy 173.99 153.67)
		)
		(stroke
			(width 0)
			(type default)
		)
	)
	(wire
		(pts
			(xy 59.69 39.37) (xy 67.31 39.37)
		)
		(stroke
			(width 0)
			(type default)
		)
	)
	(wire
		(pts
			(xy 121.92 240.03) (xy 137.16 240.03)
		)
		(stroke
			(width 0)
			(type default)
		)
	)
	(wire
		(pts
			(xy 55.88 212.09) (xy 58.42 212.09)
		)
		(stroke
			(width 0)
			(type default)
		)
	)
	(wire
		(pts
			(xy 326.39 24.13) (xy 326.39 40.64)
		)
		(stroke
			(width 0)
			(type default)
		)
	)
	(wire
		(pts
			(xy 214.63 177.8) (xy 224.79 177.8)
		)
		(stroke
			(width 0)
			(type default)
		)
	)
	(wire
		(pts
			(xy 351.79 40.64) (xy 350.52 40.64)
		)
		(stroke
			(width 0)
			(type default)
		)
	)
	(wire
		(pts
			(xy 76.2 199.39) (xy 76.2 198.12)
		)
		(stroke
			(width 0)
			(type default)
		)
	)
	(wire
		(pts
			(xy 334.01 168.91) (xy 334.01 172.72)
		)
		(stroke
			(width 0)
			(type default)
		)
	)
	(wire
		(pts
			(xy 57.15 41.91) (xy 67.31 41.91)
		)
		(stroke
			(width 0)
			(type default)
		)
	)
	(wire
		(pts
			(xy 106.68 77.47) (xy 139.7 77.47)
		)
		(stroke
			(width 0)
			(type default)
		)
	)
	(wire
		(pts
			(xy 375.92 237.49) (xy 375.92 240.03)
		)
		(stroke
			(width 0)
			(type default)
		)
	)
	(bus
		(pts
			(xy 265.43 207.01) (xy 265.43 209.55)
		)
		(stroke
			(width 0)
			(type default)
		)
	)
	(wire
		(pts
			(xy 355.6 217.17) (xy 359.41 217.17)
		)
		(stroke
			(width 0)
			(type default)
		)
	)
	(wire
		(pts
			(xy 137.16 151.13) (xy 137.16 153.67)
		)
		(stroke
			(width 0)
			(type default)
		)
	)
	(wire
		(pts
			(xy 96.52 91.44) (xy 96.52 96.52)
		)
		(stroke
			(width 0)
			(type default)
		)
	)
	(wire
		(pts
			(xy 137.16 229.87) (xy 137.16 232.41)
		)
		(stroke
			(width 0)
			(type default)
		)
	)
	(wire
		(pts
			(xy 110.49 53.34) (xy 110.49 55.88)
		)
		(stroke
			(width 0)
			(type default)
		)
	)
	(wire
		(pts
			(xy 224.79 165.1) (xy 214.63 165.1)
		)
		(stroke
			(width 0)
			(type default)
		)
	)
	(wire
		(pts
			(xy 312.42 154.94) (xy 312.42 153.67)
		)
		(stroke
			(width 0)
			(type default)
		)
	)
	(wire
		(pts
			(xy 137.16 237.49) (xy 137.16 240.03)
		)
		(stroke
			(width 0)
			(type default)
		)
	)
	(wire
		(pts
			(xy 34.29 251.46) (xy 34.29 257.81)
		)
		(stroke
			(width 0)
			(type default)
		)
	)
	(wire
		(pts
			(xy 58.42 257.81) (xy 73.66 257.81)
		)
		(stroke
			(width 0)
			(type default)
		)
	)
	(polyline
		(pts
			(xy 407.67 231.14) (xy 407.67 252.73)
		)
		(stroke
			(width 0)
			(type dash)
		)
	)
	(wire
		(pts
			(xy 397.51 48.26) (xy 405.13 48.26)
		)
		(stroke
			(width 0)
			(type default)
		)
	)
	(bus
		(pts
			(xy 369.57 49.53) (xy 369.57 52.07)
		)
		(stroke
			(width 0)
			(type default)
		)
	)
	(bus
		(pts
			(xy 369.57 147.32) (xy 369.57 149.86)
		)
		(stroke
			(width 0)
			(type default)
		)
	)
	(wire
		(pts
			(xy 248.92 58.42) (xy 288.29 58.42)
		)
		(stroke
			(width 0)
			(type default)
		)
	)
	(wire
		(pts
			(xy 104.14 165.1) (xy 104.14 167.64)
		)
		(stroke
			(width 0)
			(type default)
		)
	)
	(wire
		(pts
			(xy 149.86 33.02) (xy 149.86 35.56)
		)
		(stroke
			(width 0)
			(type default)
		)
	)
	(wire
		(pts
			(xy 342.9 96.52) (xy 347.98 96.52)
		)
		(stroke
			(width 0)
			(type default)
		)
	)
	(wire
		(pts
			(xy 166.37 45.72) (xy 139.7 45.72)
		)
		(stroke
			(width 0)
			(type default)
		)
	)
	(wire
		(pts
			(xy 106.68 77.47) (xy 106.68 85.09)
		)
		(stroke
			(width 0)
			(type default)
		)
	)
	(wire
		(pts
			(xy 313.69 213.36) (xy 312.42 213.36)
		)
		(stroke
			(width 0)
			(type default)
		)
	)
	(wire
		(pts
			(xy 165.1 83.82) (xy 165.1 90.17)
		)
		(stroke
			(width 0)
			(type default)
		)
	)
	(wire
		(pts
			(xy 269.24 143.51) (xy 280.67 143.51)
		)
		(stroke
			(width 0)
			(type default)
		)
	)
	(wire
		(pts
			(xy 331.47 208.28) (xy 337.82 208.28)
		)
		(stroke
			(width 0)
			(type default)
		)
	)
	(wire
		(pts
			(xy 298.45 138.43) (xy 313.69 138.43)
		)
		(stroke
			(width 0)
			(type default)
		)
	)
	(polyline
		(pts
			(xy 201.93 162.56) (xy 407.67 162.56)
		)
		(stroke
			(width 0)
			(type dot)
		)
	)
	(wire
		(pts
			(xy 350.52 138.43) (xy 350.52 140.97)
		)
		(stroke
			(width 0)
			(type default)
		)
	)
	(wire
		(pts
			(xy 113.03 85.09) (xy 106.68 85.09)
		)
		(stroke
			(width 0)
			(type default)
		)
	)
	(wire
		(pts
			(xy 279.4 267.97) (xy 294.64 267.97)
		)
		(stroke
			(width 0)
			(type default)
		)
	)
	(wire
		(pts
			(xy 128.27 175.26) (xy 128.27 176.53)
		)
		(stroke
			(width 0)
			(type default)
		)
	)
	(bus
		(pts
			(xy 297.18 254) (xy 295.91 254)
		)
		(stroke
			(width 0)
			(type default)
		)
	)
	(wire
		(pts
			(xy 300.99 172.72) (xy 313.69 172.72)
		)
		(stroke
			(width 0)
			(type default)
		)
	)
	(polyline
		(pts
			(xy 274.32 81.28) (xy 274.32 63.5)
		)
		(stroke
			(width 0)
			(type default)
		)
	)
	(wire
		(pts
			(xy 154.94 168.91) (xy 173.99 168.91)
		)
		(stroke
			(width 0)
			(type default)
		)
	)
	(wire
		(pts
			(xy 318.77 34.29) (xy 318.77 31.75)
		)
		(stroke
			(width 0)
			(type default)
		)
	)
	(wire
		(pts
			(xy 147.32 81.28) (xy 147.32 83.82)
		)
		(stroke
			(width 0)
			(type default)
		)
	)
	(wire
		(pts
			(xy 157.48 33.02) (xy 157.48 35.56)
		)
		(stroke
			(width 0)
			(type default)
		)
	)
	(wire
		(pts
			(xy 157.48 25.4) (xy 165.1 25.4)
		)
		(stroke
			(width 0)
			(type default)
		)
	)
	(wire
		(pts
			(xy 327.66 43.18) (xy 326.39 43.18)
		)
		(stroke
			(width 0)
			(type default)
		)
	)
	(wire
		(pts
			(xy 345.44 205.74) (xy 337.82 205.74)
		)
		(stroke
			(width 0)
			(type default)
		)
	)
	(wire
		(pts
			(xy 173.99 125.73) (xy 173.99 128.27)
		)
		(stroke
			(width 0)
			(type default)
		)
	)
	(wire
		(pts
			(xy 377.19 185.42) (xy 377.19 190.5)
		)
		(stroke
			(width 0)
			(type default)
		)
	)
	(wire
		(pts
			(xy 121.92 245.11) (xy 135.89 245.11)
		)
		(stroke
			(width 0)
			(type default)
		)
	)
	(wire
		(pts
			(xy 58.42 245.11) (xy 72.39 245.11)
		)
		(stroke
			(width 0)
			(type default)
		)
	)
	(wire
		(pts
			(xy 341.63 245.11) (xy 341.63 246.38)
		)
		(stroke
			(width 0)
			(type default)
		)
	)
	(wire
		(pts
			(xy 214.63 210.82) (xy 238.76 210.82)
		)
		(stroke
			(width 0)
			(type default)
		)
	)
	(bus
		(pts
			(xy 267.97 182.88) (xy 266.7 182.88)
		)
		(stroke
			(width 0)
			(type default)
		)
	)
	(wire
		(pts
			(xy 64.77 133.35) (xy 64.77 135.89)
		)
		(stroke
			(width 0)
			(type default)
		)
	)
	(wire
		(pts
			(xy 116.84 90.17) (xy 116.84 96.52)
		)
		(stroke
			(width 0)
			(type default)
		)
	)
	(wire
		(pts
			(xy 58.42 238.76) (xy 73.66 238.76)
		)
		(stroke
			(width 0)
			(type default)
		)
	)
	(wire
		(pts
			(xy 313.69 187.96) (xy 312.42 187.96)
		)
		(stroke
			(width 0)
			(type default)
		)
	)
	(wire
		(pts
			(xy 62.23 34.29) (xy 78.74 34.29)
		)
		(stroke
			(width 0)
			(type default)
		)
	)
	(wire
		(pts
			(xy 360.68 91.44) (xy 360.68 95.25)
		)
		(stroke
			(width 0)
			(type default)
		)
	)
	(bus
		(pts
			(xy 370.84 72.39) (xy 373.38 72.39)
		)
		(stroke
			(width 0)
			(type default)
		)
	)
	(wire
		(pts
			(xy 321.31 245.11) (xy 321.31 246.38)
		)
		(stroke
			(width 0)
			(type default)
		)
	)
	(wire
		(pts
			(xy 243.84 189.23) (xy 264.16 189.23)
		)
		(stroke
			(width 0)
			(type default)
		)
	)
	(wire
		(pts
			(xy 104.14 167.64) (xy 104.14 170.18)
		)
		(stroke
			(width 0)
			(type default)
		)
	)
	(bus
		(pts
			(xy 369.57 62.23) (xy 369.57 64.77)
		)
		(stroke
			(width 0)
			(type default)
		)
	)
	(wire
		(pts
			(xy 148.59 58.42) (xy 166.37 58.42)
		)
		(stroke
			(width 0)
			(type default)
		)
	)
	(bus
		(pts
			(xy 43.18 101.6) (xy 41.91 101.6)
		)
		(stroke
			(width 0)
			(type default)
		)
	)
	(bus
		(pts
			(xy 325.12 106.68) (xy 323.85 106.68)
		)
		(stroke
			(width 0)
			(type default)
		)
	)
	(wire
		(pts
			(xy 116.84 175.26) (xy 116.84 176.53)
		)
		(stroke
			(width 0)
			(type default)
		)
	)
	(wire
		(pts
			(xy 254 64.77) (xy 259.08 64.77)
		)
		(stroke
			(width 0)
			(type default)
		)
	)
	(label "USB_USER.VM"
		(at 351.79 53.34 0)
		(effects
			(font
				(size 1.27 1.27)
			)
			(justify left bottom)
		)
	)
	(label "USB_HOST_VBUS"
		(at 78.74 34.29 180)
		(effects
			(font
				(size 1.27 1.27)
			)
			(justify right bottom)
		)
	)
	(label "BDBUS1"
		(at 224.79 167.64 180)
		(effects
			(font
				(size 1.27 1.27)
			)
			(justify right bottom)
		)
	)
	(label "USB_DBG_CONN_D-"
		(at 154.94 168.91 0)
		(effects
			(font
				(size 1.27 1.27)
			)
			(justify left bottom)
		)
	)
	(label "FTDI_EECS"
		(at 161.29 187.96 0)
		(effects
			(font
				(size 1.27 1.27)
			)
			(justify left bottom)
		)
	)
	(label "I2C.SDA"
		(at 387.35 217.17 180)
		(effects
			(font
				(size 1.27 1.27)
			)
			(justify right bottom)
		)
	)
	(label "FTDI_3V3"
		(at 146.05 180.34 0)
		(effects
			(font
				(size 1.27 1.27)
			)
			(justify left bottom)
		)
	)
	(label "USB_HOST_VBUS_EN"
		(at 36.83 87.63 0)
		(effects
			(font
				(size 1.27 1.27)
			)
			(justify left bottom)
		)
	)
	(label "USB_USR_CONN_D+"
		(at 252.73 60.96 0)
		(effects
			(font
				(size 1.27 1.27)
			)
			(justify left bottom)
		)
	)
	(label "~{BDBUS3}"
		(at 368.3 172.72 180)
		(effects
			(font
				(size 1.27 1.27)
			)
			(justify right bottom)
		)
	)
	(label "FTDI_SDA_IN"
		(at 294.64 273.05 180)
		(effects
			(font
				(size 1.27 1.27)
			)
			(justify right bottom)
		)
	)
	(label "FTDI_3V3"
		(at 298.45 138.43 0)
		(effects
			(font
				(size 1.27 1.27)
			)
			(justify left bottom)
		)
	)
	(label "USB_USER.VPO"
		(at 351.79 58.42 0)
		(effects
			(font
				(size 1.27 1.27)
			)
			(justify left bottom)
		)
	)
	(label "BDBUS2"
		(at 252.73 273.05 0)
		(effects
			(font
				(size 1.27 1.27)
			)
			(justify left bottom)
		)
	)
	(label "BDBUS2"
		(at 224.79 170.18 180)
		(effects
			(font
				(size 1.27 1.27)
			)
			(justify right bottom)
		)
	)
	(label "USB_USER.RCV"
		(at 351.79 63.5 0)
		(effects
			(font
				(size 1.27 1.27)
			)
			(justify left bottom)
		)
	)
	(label "FTDI_UART1_TX"
		(at 215.9 208.28 0)
		(effects
			(font
				(size 1.27 1.27)
			)
			(justify left bottom)
		)
	)
	(label "JTAG.RST"
		(at 271.78 143.51 0)
		(effects
			(font
				(size 1.27 1.27)
			)
			(justify left bottom)
		)
	)
	(label "FTDI_REF"
		(at 172.72 220.98 180)
		(effects
			(font
				(size 1.27 1.27)
			)
			(justify right bottom)
		)
	)
	(label "FTDI_SCL"
		(at 332.74 210.82 0)
		(effects
			(font
				(size 1.27 1.27)
			)
			(justify left bottom)
		)
	)
	(label "FTDI_JTAG_TCK"
		(at 229.87 143.51 180)
		(effects
			(font
				(size 1.27 1.27)
			)
			(justify right bottom)
		)
	)
	(label "USB_USR_VBUS"
		(at 325.12 76.2 180)
		(effects
			(font
				(size 1.27 1.27)
			)
			(justify right bottom)
		)
	)
	(label "FTDI_SDA_OUT"
		(at 294.64 270.51 180)
		(effects
			(font
				(size 1.27 1.27)
			)
			(justify right bottom)
		)
	)
	(label "FTDI_XO"
		(at 162.56 203.2 0)
		(effects
			(font
				(size 1.27 1.27)
			)
			(justify left bottom)
		)
	)
	(label "FTDI_EECLK"
		(at 135.89 245.11 180)
		(effects
			(font
				(size 1.27 1.27)
			)
			(justify right bottom)
		)
	)
	(label "FTDI_VPHY"
		(at 152.4 125.73 0)
		(effects
			(font
				(size 1.27 1.27)
			)
			(justify left bottom)
		)
	)
	(label "USB_USER.SPD"
		(at 351.79 50.8 0)
		(effects
			(font
				(size 1.27 1.27)
			)
			(justify left bottom)
		)
	)
	(label "JTAG.TMS"
		(at 355.6 146.05 0)
		(effects
			(font
				(size 1.27 1.27)
			)
			(justify left bottom)
		)
	)
	(label "JTAG.TCK"
		(at 355.6 143.51 0)
		(effects
			(font
				(size 1.27 1.27)
			)
			(justify left bottom)
		)
	)
	(label "FTDI_VCORE"
		(at 154.94 158.75 0)
		(effects
			(font
				(size 1.27 1.27)
			)
			(justify left bottom)
		)
	)
	(label "USB_USR_VBUS"
		(at 259.08 43.18 180)
		(effects
			(font
				(size 1.27 1.27)
			)
			(justify right bottom)
		)
	)
	(label "FTDI_3V3"
		(at 314.96 237.49 0)
		(effects
			(font
				(size 1.27 1.27)
			)
			(justify left bottom)
		)
	)
	(label "USB_HOST.CLK"
		(at 148.59 58.42 0)
		(effects
			(font
				(size 1.27 1.27)
			)
			(justify left bottom)
		)
	)
	(label "USB_HOST.GPX"
		(at 148.59 68.58 0)
		(effects
			(font
				(size 1.27 1.27)
			)
			(justify left bottom)
		)
	)
	(label "USB_DBG_PD.VBUS"
		(at 69.85 165.1 0)
		(effects
			(font
				(size 1.27 1.27)
			)
			(justify left bottom)
		)
	)
	(label "FTDI_3V3"
		(at 135.89 125.73 0)
		(effects
			(font
				(size 1.27 1.27)
			)
			(justify left bottom)
		)
	)
	(label "LED_TX0"
		(at 92.71 245.11 0)
		(effects
			(font
				(size 1.27 1.27)
			)
			(justify left bottom)
		)
	)
	(label "FTDI_JTAG_TMS"
		(at 229.87 151.13 180)
		(effects
			(font
				(size 1.27 1.27)
			)
			(justify right bottom)
		)
	)
	(label "USB_USR_D+"
		(at 313.69 60.96 0)
		(effects
			(font
				(size 1.27 1.27)
			)
			(justify left bottom)
		)
	)
	(label "I2C.SCL"
		(at 294.64 264.16 180)
		(effects
			(font
				(size 1.27 1.27)
			)
			(justify right bottom)
		)
	)
	(label "I2C_EN"
		(at 224.79 177.8 180)
		(effects
			(font
				(size 1.27 1.27)
			)
			(justify right bottom)
		)
	)
	(label "I2C.QDCDC2_SCL"
		(at 243.84 262.89 0)
		(effects
			(font
				(size 1.27 1.27)
			)
			(justify left bottom)
		)
	)
	(label "USB_USER.~{OE}"
		(at 372.11 45.72 0)
		(effects
			(font
				(size 1.27 1.27)
			)
			(justify left bottom)
		)
	)
	(label "USB_DBG_CONN_D+"
		(at 154.94 166.37 0)
		(effects
			(font
				(size 1.27 1.27)
			)
			(justify left bottom)
		)
	)
	(label "USB_USER.VMO"
		(at 351.79 60.96 0)
		(effects
			(font
				(size 1.27 1.27)
			)
			(justify left bottom)
		)
	)
	(label "USB_HOST_CONN_D+"
		(at 80.01 41.91 0)
		(effects
			(font
				(size 1.27 1.27)
			)
			(justify left bottom)
		)
	)
	(label "USB_HOST.INT"
		(at 128.27 53.34 0)
		(effects
			(font
				(size 1.27 1.27)
			)
			(justify left bottom)
		)
	)
	(label "BDBUS3"
		(at 214.63 245.11 0)
		(effects
			(font
				(size 1.27 1.27)
			)
			(justify left bottom)
		)
	)
	(label "SPI_EN"
		(at 224.79 175.26 180)
		(effects
			(font
				(size 1.27 1.27)
			)
			(justify right bottom)
		)
	)
	(label "UART0.RX"
		(at 251.46 186.69 0)
		(effects
			(font
				(size 1.27 1.27)
			)
			(justify left bottom)
		)
	)
	(label "USB_DBG_PD.CC1"
		(at 74.93 181.61 0)
		(effects
			(font
				(size 1.27 1.27)
			)
			(justify left bottom)
		)
	)
	(label "USB_USER.SUS"
		(at 351.79 48.26 0)
		(effects
			(font
				(size 1.27 1.27)
			)
			(justify left bottom)
		)
	)
	(label "FTDI_UART1_RX"
		(at 215.9 210.82 0)
		(effects
			(font
				(size 1.27 1.27)
			)
			(justify left bottom)
		)
	)
	(label "USB_USR_VPU"
		(at 313.69 50.8 0)
		(effects
			(font
				(size 1.27 1.27)
			)
			(justify left bottom)
		)
	)
	(label "USB_HOST.~{RESET}"
		(at 148.59 55.88 0)
		(effects
			(font
				(size 1.27 1.27)
			)
			(justify left bottom)
		)
	)
	(label "LED_RX0"
		(at 92.71 247.65 0)
		(effects
			(font
				(size 1.27 1.27)
			)
			(justify left bottom)
		)
	)
	(label "FTDI_JTAG_RST"
		(at 234.95 143.51 0)
		(effects
			(font
				(size 1.27 1.27)
			)
			(justify left bottom)
		)
	)
	(label "USB_HOST.MOSI"
		(at 148.59 66.04 0)
		(effects
			(font
				(size 1.27 1.27)
			)
			(justify left bottom)
		)
	)
	(label "USB_HOST_CONN_D-"
		(at 80.01 39.37 0)
		(effects
			(font
				(size 1.27 1.27)
			)
			(justify left bottom)
		)
	)
	(label "USB_HOST_XI"
		(at 139.7 77.47 180)
		(effects
			(font
				(size 1.27 1.27)
			)
			(justify right bottom)
		)
	)
	(label "FTDI_JTAG_TMS"
		(at 298.45 146.05 0)
		(effects
			(font
				(size 1.27 1.27)
			)
			(justify left bottom)
		)
	)
	(label "USB_DBG_CONN_D-"
		(at 93.98 191.77 180)
		(effects
			(font
				(size 1.27 1.27)
			)
			(justify right bottom)
		)
	)
	(label "USB_USR_CONN_D-"
		(at 252.73 58.42 0)
		(effects
			(font
				(size 1.27 1.27)
			)
			(justify left bottom)
		)
	)
	(label "USB_HOST_VBUS"
		(at 93.98 82.55 180)
		(effects
			(font
				(size 1.27 1.27)
			)
			(justify right bottom)
		)
	)
	(label "FTDI_PWREN"
		(at 135.89 240.03 180)
		(effects
			(font
				(size 1.27 1.27)
			)
			(justify right bottom)
		)
	)
	(label "USB_USER.~{OE}"
		(at 351.79 45.72 0)
		(effects
			(font
				(size 1.27 1.27)
			)
			(justify left bottom)
		)
	)
	(label "LED_TX1"
		(at 92.71 250.19 0)
		(effects
			(font
				(size 1.27 1.27)
			)
			(justify left bottom)
		)
	)
	(label "FTDI_SDA_IN"
		(at 332.74 218.44 0)
		(effects
			(font
				(size 1.27 1.27)
			)
			(justify left bottom)
		)
	)
	(label "BDBUS1"
		(at 302.26 215.9 0)
		(effects
			(font
				(size 1.27 1.27)
			)
			(justify left bottom)
		)
	)
	(label "FTDI_EECLK"
		(at 161.29 190.5 0)
		(effects
			(font
				(size 1.27 1.27)
			)
			(justify left bottom)
		)
	)
	(label "FTDI_SDA_OUT"
		(at 332.74 215.9 0)
		(effects
			(font
				(size 1.27 1.27)
			)
			(justify left bottom)
		)
	)
	(label "JTAG.TDI"
		(at 355.6 148.59 0)
		(effects
			(font
				(size 1.27 1.27)
			)
			(justify left bottom)
		)
	)
	(label "FTDI_JTAG_TCK"
		(at 298.45 143.51 0)
		(effects
			(font
				(size 1.27 1.27)
			)
			(justify left bottom)
		)
	)
	(label "USB_HOST_XO"
		(at 139.7 85.09 180)
		(effects
			(font
				(size 1.27 1.27)
			)
			(justify right bottom)
		)
	)
	(label "FTDI_JTAG_TDO"
		(at 229.87 148.59 180)
		(effects
			(font
				(size 1.27 1.27)
			)
			(justify right bottom)
		)
	)
	(label "FTDI_3V3"
		(at 95.25 143.51 0)
		(effects
			(font
				(size 1.27 1.27)
			)
			(justify left bottom)
		)
	)
	(label "BDBUS2"
		(at 300.99 185.42 0)
		(effects
			(font
				(size 1.27 1.27)
			)
			(justify left bottom)
		)
	)
	(label "FTDI_JTAG_TDI"
		(at 298.45 148.59 0)
		(effects
			(font
				(size 1.27 1.27)
			)
			(justify left bottom)
		)
	)
	(label "USB_USR_CC2"
		(at 252.73 50.8 0)
		(effects
			(font
				(size 1.27 1.27)
			)
			(justify left bottom)
		)
	)
	(label "~{BDBUS3}"
		(at 265.43 233.68 180)
		(effects
			(font
				(size 1.27 1.27)
			)
			(justify right bottom)
		)
	)
	(label "USB_USER.VBUS_PEN"
		(at 325.12 100.33 0)
		(effects
			(font
				(size 1.27 1.27)
			)
			(justify left bottom)
		)
	)
	(label "USB_HOST.~{RESET}"
		(at 128.27 55.88 0)
		(effects
			(font
				(size 1.27 1.27)
			)
			(justify left bottom)
		)
	)
	(label "BDBUS2"
		(at 302.26 218.44 0)
		(effects
			(font
				(size 1.27 1.27)
			)
			(justify left bottom)
		)
	)
	(label "FTDI_3V3"
		(at 80.01 133.35 180)
		(effects
			(font
				(size 1.27 1.27)
			)
			(justify right bottom)
		)
	)
	(label "FTDI_3V3"
		(at 146.05 229.87 180)
		(effects
			(font
				(size 1.27 1.27)
			)
			(justify right bottom)
		)
	)
	(label "BDBUS0"
		(at 302.26 210.82 0)
		(effects
			(font
				(size 1.27 1.27)
			)
			(justify left bottom)
		)
	)
	(label "USB_USR_D-"
		(at 313.69 58.42 0)
		(effects
			(font
				(size 1.27 1.27)
			)
			(justify left bottom)
		)
	)
	(label "BDBUS1"
		(at 300.99 180.34 0)
		(effects
			(font
				(size 1.27 1.27)
			)
			(justify left bottom)
		)
	)
	(label "USB_HOST_D-"
		(at 152.4 45.72 0)
		(effects
			(font
				(size 1.27 1.27)
			)
			(justify left bottom)
		)
	)
	(label "FTDI_3V3"
		(at 302.26 205.74 0)
		(effects
			(font
				(size 1.27 1.27)
			)
			(justify left bottom)
		)
	)
	(label "UART1.TX"
		(at 251.46 210.82 0)
		(effects
			(font
				(size 1.27 1.27)
			)
			(justify left bottom)
		)
	)
	(label "JTAG.TDO"
		(at 355.6 151.13 0)
		(effects
			(font
				(size 1.27 1.27)
			)
			(justify left bottom)
		)
	)
	(label "USB_DBG_CONN_D+"
		(at 93.98 189.23 180)
		(effects
			(font
				(size 1.27 1.27)
			)
			(justify right bottom)
		)
	)
	(label "USB_HOST.INT"
		(at 148.59 53.34 0)
		(effects
			(font
				(size 1.27 1.27)
			)
			(justify left bottom)
		)
	)
	(label "FTDI_3V3"
		(at 300.99 172.72 0)
		(effects
			(font
				(size 1.27 1.27)
			)
			(justify left bottom)
		)
	)
	(label "SPI_EN"
		(at 368.3 175.26 180)
		(effects
			(font
				(size 1.27 1.27)
			)
			(justify right bottom)
		)
	)
	(label "FTDI_3V3"
		(at 88.9 125.73 0)
		(effects
			(font
				(size 1.27 1.27)
			)
			(justify left bottom)
		)
	)
	(label "FTDI_EEDAT"
		(at 135.89 250.19 180)
		(effects
			(font
				(size 1.27 1.27)
			)
			(justify right bottom)
		)
	)
	(label "FTDI_EEDAT"
		(at 161.29 193.04 0)
		(effects
			(font
				(size 1.27 1.27)
			)
			(justify left bottom)
		)
	)
	(label "LED_RX1"
		(at 92.71 252.73 0)
		(effects
			(font
				(size 1.27 1.27)
			)
			(justify left bottom)
		)
	)
	(label "FTDI_JTAG_TDI"
		(at 229.87 146.05 180)
		(effects
			(font
				(size 1.27 1.27)
			)
			(justify right bottom)
		)
	)
	(label "USB_USR_CC1"
		(at 252.73 48.26 0)
		(effects
			(font
				(size 1.27 1.27)
			)
			(justify left bottom)
		)
	)
	(label "FTDI_VPLL"
		(at 154.94 156.21 0)
		(effects
			(font
				(size 1.27 1.27)
			)
			(justify left bottom)
		)
	)
	(label "FTDI_VCORE"
		(at 128.27 167.64 180)
		(effects
			(font
				(size 1.27 1.27)
			)
			(justify right bottom)
		)
	)
	(label "BDBUS0"
		(at 252.73 267.97 0)
		(effects
			(font
				(size 1.27 1.27)
			)
			(justify left bottom)
		)
	)
	(label "I2C_EN"
		(at 367.03 208.28 180)
		(effects
			(font
				(size 1.27 1.27)
			)
			(justify right bottom)
		)
	)
	(label "USB_USR_VBUS"
		(at 398.78 86.36 180)
		(effects
			(font
				(size 1.27 1.27)
			)
			(justify right bottom)
		)
	)
	(label "USB_HOST.~{CS}"
		(at 148.59 60.96 0)
		(effects
			(font
				(size 1.27 1.27)
			)
			(justify left bottom)
		)
	)
	(label "USB_HOST.MISO"
		(at 148.59 63.5 0)
		(effects
			(font
				(size 1.27 1.27)
			)
			(justify left bottom)
		)
	)
	(label "BDBUS0"
		(at 300.99 177.8 0)
		(effects
			(font
				(size 1.27 1.27)
			)
			(justify left bottom)
		)
	)
	(label "BDBUS3"
		(at 224.79 172.72 180)
		(effects
			(font
				(size 1.27 1.27)
			)
			(justify right bottom)
		)
	)
	(label "FTDI_VPHY"
		(at 154.94 153.67 0)
		(effects
			(font
				(size 1.27 1.27)
			)
			(justify left bottom)
		)
	)
	(label "USB_USER.VP"
		(at 351.79 55.88 0)
		(effects
			(font
				(size 1.27 1.27)
			)
			(justify left bottom)
		)
	)
	(label "USB_USER.SCON"
		(at 351.79 66.04 0)
		(effects
			(font
				(size 1.27 1.27)
			)
			(justify left bottom)
		)
	)
	(label "I2C.QDCDC1_SCL"
		(at 243.84 265.43 0)
		(effects
			(font
				(size 1.27 1.27)
			)
			(justify left bottom)
		)
	)
	(label "UART0.TX"
		(at 251.46 189.23 0)
		(effects
			(font
				(size 1.27 1.27)
			)
			(justify left bottom)
		)
	)
	(label "USB_HOST_VBCOMP"
		(at 147.32 81.28 0)
		(effects
			(font
				(size 1.27 1.27)
			)
			(justify left bottom)
		)
	)
	(label "FTDI_JTAG_TDO"
		(at 298.45 151.13 0)
		(effects
			(font
				(size 1.27 1.27)
			)
			(justify left bottom)
		)
	)
	(label "FTDI_SCL"
		(at 294.64 267.97 180)
		(effects
			(font
				(size 1.27 1.27)
			)
			(justify right bottom)
		)
	)
	(label "USB_USER.VDET"
		(at 316.23 100.33 90)
		(effects
			(font
				(size 1.27 1.27)
			)
			(justify left bottom)
		)
	)
	(label "BDBUS1"
		(at 252.73 270.51 0)
		(effects
			(font
				(size 1.27 1.27)
			)
			(justify left bottom)
		)
	)
	(label "FTDI_EECS"
		(at 135.89 247.65 180)
		(effects
			(font
				(size 1.27 1.27)
			)
			(justify right bottom)
		)
	)
	(label "BDBUS3"
		(at 300.99 182.88 0)
		(effects
			(font
				(size 1.27 1.27)
			)
			(justify left bottom)
		)
	)
	(label "USB_DBG_PD.VBUS"
		(at 16.51 133.35 0)
		(effects
			(font
				(size 1.27 1.27)
			)
			(justify left bottom)
		)
	)
	(label "USB_HOST_XO"
		(at 152.4 76.2 0)
		(effects
			(font
				(size 1.27 1.27)
			)
			(justify left bottom)
		)
	)
	(label "FTDI_VPLL"
		(at 105.41 125.73 0)
		(effects
			(font
				(size 1.27 1.27)
			)
			(justify left bottom)
		)
	)
	(label "BDBUS0"
		(at 224.79 165.1 180)
		(effects
			(font
				(size 1.27 1.27)
			)
			(justify right bottom)
		)
	)
	(label "UART1.RX"
		(at 251.46 208.28 0)
		(effects
			(font
				(size 1.27 1.27)
			)
			(justify left bottom)
		)
	)
	(label "USB_HOST_VBUS_FLG"
		(at 38.1 85.09 0)
		(effects
			(font
				(size 1.27 1.27)
			)
			(justify left bottom)
		)
	)
	(label "FTDI_PWREN"
		(at 226.06 231.14 180)
		(effects
			(font
				(size 1.27 1.27)
			)
			(justify right bottom)
		)
	)
	(label "I2C.SCL"
		(at 387.35 210.82 180)
		(effects
			(font
				(size 1.27 1.27)
			)
			(justify right bottom)
		)
	)
	(label "FTDI_SPI.~{CS}"
		(at 368.3 182.88 180)
		(effects
			(font
				(size 1.27 1.27)
			)
			(justify right bottom)
		)
	)
	(label "FTDI_XI"
		(at 162.56 198.12 0)
		(effects
			(font
				(size 1.27 1.27)
			)
			(justify left bottom)
		)
	)
	(label "USB_HOST_XI"
		(at 152.4 73.66 0)
		(effects
			(font
				(size 1.27 1.27)
			)
			(justify left bottom)
		)
	)
	(label "FTDI_3V3"
		(at 242.57 135.89 0)
		(effects
			(font
				(size 1.27 1.27)
			)
			(justify left bottom)
		)
	)
	(label "FTDI_UART0_TX"
		(at 215.9 186.69 0)
		(effects
			(font
				(size 1.27 1.27)
			)
			(justify left bottom)
		)
	)
	(label "FTDI_RST"
		(at 161.29 180.34 0)
		(effects
			(font
				(size 1.27 1.27)
			)
			(justify left bottom)
		)
	)
	(label "FTDI_3V3"
		(at 242.57 223.52 0)
		(effects
			(font
				(size 1.27 1.27)
			)
			(justify left bottom)
		)
	)
	(label "USB_USER.SUS"
		(at 372.11 48.26 0)
		(effects
			(font
				(size 1.27 1.27)
			)
			(justify left bottom)
		)
	)
	(label "USB_DBG_PD.CC2"
		(at 74.93 184.15 0)
		(effects
			(font
				(size 1.27 1.27)
			)
			(justify left bottom)
		)
	)
	(label "BDBUS3"
		(at 367.03 205.74 180)
		(effects
			(font
				(size 1.27 1.27)
			)
			(justify right bottom)
		)
	)
	(label "FTDI_SPI.MOSI"
		(at 368.3 180.34 180)
		(effects
			(font
				(size 1.27 1.27)
			)
			(justify right bottom)
		)
	)
	(label "USB_HOST_D+"
		(at 152.4 48.26 0)
		(effects
			(font
				(size 1.27 1.27)
			)
			(justify left bottom)
		)
	)
	(label "FTDI_SPI.MISO"
		(at 368.3 185.42 180)
		(effects
			(font
				(size 1.27 1.27)
			)
			(justify right bottom)
		)
	)
	(label "FTDI_SPI.SCK"
		(at 368.3 177.8 180)
		(effects
			(font
				(size 1.27 1.27)
			)
			(justify right bottom)
		)
	)
	(label "USB_HOST.VBUS_PEN"
		(at 43.18 96.52 180)
		(effects
			(font
				(size 1.27 1.27)
			)
			(justify right bottom)
		)
	)
	(label "FTDI_JTAG_RST"
		(at 229.87 156.21 180)
		(effects
			(font
				(size 1.27 1.27)
			)
			(justify right bottom)
		)
	)
	(label "FTDI_UART0_RX"
		(at 215.9 189.23 0)
		(effects
			(font
				(size 1.27 1.27)
			)
			(justify left bottom)
		)
	)
	(global_label "FTDI_DIS"
		(shape input)
		(at 354.33 138.43 0)
		(fields_autoplaced yes)
		(effects
			(font
				(size 1.27 1.27)
			)
			(justify left)
		)
		(property "Intersheetrefs" "${INTERSHEET_REFS}"
			(at 364.726 138.5094 0)
			(effects
				(font
					(size 1.27 1.27)
				)
				(justify left)
				(hide yes)
			)
		)
	)
	(global_label "FTDI_DIS"
		(shape input)
		(at 264.16 275.59 180)
		(fields_autoplaced yes)
		(effects
			(font
				(size 1.27 1.27)
			)
			(justify right)
		)
		(property "Intersheetrefs" "${INTERSHEET_REFS}"
			(at 253.764 275.5106 0)
			(effects
				(font
					(size 1.27 1.27)
				)
				(justify right)
				(hide yes)
			)
		)
	)
	(hierarchical_label "I2C{I2C}"
		(shape bidirectional)
		(at 238.76 257.81 180)
		(effects
			(font
				(size 1.27 1.27)
			)
			(justify right)
		)
	)
	(hierarchical_label "JTAG{JTAG}"
		(shape bidirectional)
		(at 283.21 143.51 0)
		(effects
			(font
				(size 1.27 1.27)
			)
			(justify left)
		)
	)
	(hierarchical_label "UART1{UART}"
		(shape bidirectional)
		(at 267.97 204.47 0)
		(effects
			(font
				(size 1.27 1.27)
			)
			(justify left)
		)
	)
	(hierarchical_label "USB_HOST{SPI-USB}"
		(shape bidirectional)
		(at 41.91 101.6 180)
		(effects
			(font
				(size 1.27 1.27)
			)
			(justify right)
		)
	)
	(hierarchical_label "USB_DBG_PD{USB-C-PD}"
		(shape bidirectional)
		(at 91.44 153.67 180)
		(effects
			(font
				(size 1.27 1.27)
			)
			(justify right)
		)
	)
	(hierarchical_label "USB_HOST{SPI-USB}"
		(shape bidirectional)
		(at 142.24 71.12 180)
		(effects
			(font
				(size 1.27 1.27)
			)
			(justify right)
		)
	)
	(hierarchical_label "UART0{UART}"
		(shape bidirectional)
		(at 267.97 182.88 0)
		(effects
			(font
				(size 1.27 1.27)
			)
			(justify left)
		)
	)
	(hierarchical_label "USB_USER{USB-FPGA-PHY}"
		(shape bidirectional)
		(at 325.12 106.68 0)
		(effects
			(font
				(size 1.27 1.27)
			)
			(justify left)
		)
	)
	(hierarchical_label "JTAG{JTAG}"
		(shape bidirectional)
		(at 373.38 138.43 0)
		(effects
			(font
				(size 1.27 1.27)
			)
			(justify left)
		)
	)
	(hierarchical_label "USB_USER{USB-FPGA-PHY}"
		(shape bidirectional)
		(at 373.38 72.39 0)
		(effects
			(font
				(size 1.27 1.27)
			)
			(justify left)
		)
	)
	(hierarchical_label "I2C{I2C}"
		(shape bidirectional)
		(at 295.91 254 180)
		(effects
			(font
				(size 1.27 1.27)
			)
			(justify right)
		)
	)
	(hierarchical_label "FTDI_SPI{SPI}"
		(shape bidirectional)
		(at 372.11 172.72 0)
		(effects
			(font
				(size 1.27 1.27)
			)
			(justify left)
		)
	)
	(hierarchical_label "I2C{I2C}"
		(shape bidirectional)
		(at 389.89 208.28 0)
		(effects
			(font
				(size 1.27 1.27)
			)
			(justify left)
		)
	)
	(symbol
		(lib_id "antmicropower:GND")
		(at 140.97 218.44 0)
		(unit 1)
		(exclude_from_sim no)
		(in_bom yes)
		(on_board yes)
		(dnp no)
		(property "Reference" "#PWR0226"
			(at 140.97 224.79 0)
			(effects
				(font
					(size 1.27 1.27)
				)
				(hide yes)
			)
		)
		(property "Value" "GND"
			(at 140.97 222.25 0)
			(effects
				(font
					(size 1.27 1.27)
				)
			)
		)
		(property "Footprint" ""
			(at 149.86 226.06 0)
			(effects
				(font
					(size 1.27 1.27)
					(thickness 0.15)
				)
				(justify left bottom)
				(hide yes)
			)
		)
		(property "Datasheet" ""
			(at 149.86 231.14 0)
			(effects
				(font
					(size 1.27 1.27)
					(thickness 0.15)
				)
				(justify left bottom)
				(hide yes)
			)
		)
		(property "Description" ""
			(at 140.97 218.44 0)
			(effects
				(font
					(size 1.27 1.27)
				)
			)
		)
		(property "Author" "Antmicro"
			(at 149.86 226.06 0)
			(effects
				(font
					(size 1.27 1.27)
					(thickness 0.15)
				)
				(justify left bottom)
				(hide yes)
			)
		)
		(property "License" "Apache-2.0"
			(at 149.86 228.6 0)
			(effects
				(font
					(size 1.27 1.27)
					(thickness 0.15)
				)
				(justify left bottom)
				(hide yes)
			)
		)
		(pin "1"
		)
		(instances
			(project "k410t-devboard"
				(path ""
					(reference "#PWR0226")
					(unit 1)
				)
			)
		)
	)
	(symbol
		(lib_id "antmicropower:GND")
		(at 115.57 134.62 0)
		(mirror y)
		(unit 1)
		(exclude_from_sim no)
		(in_bom yes)
		(on_board yes)
		(dnp no)
		(property "Reference" "#PWR0215"
			(at 115.57 140.97 0)
			(effects
				(font
					(size 1.27 1.27)
				)
				(hide yes)
			)
		)
		(property "Value" "GND"
			(at 115.57 138.43 0)
			(effects
				(font
					(size 1.27 1.27)
				)
			)
		)
		(property "Footprint" ""
			(at 106.68 142.24 0)
			(effects
				(font
					(size 1.27 1.27)
					(thickness 0.15)
				)
				(justify left bottom)
				(hide yes)
			)
		)
		(property "Datasheet" ""
			(at 106.68 147.32 0)
			(effects
				(font
					(size 1.27 1.27)
					(thickness 0.15)
				)
				(justify left bottom)
				(hide yes)
			)
		)
		(property "Description" ""
			(at 115.57 134.62 0)
			(effects
				(font
					(size 1.27 1.27)
				)
			)
		)
		(property "Author" "Antmicro"
			(at 106.68 142.24 0)
			(effects
				(font
					(size 1.27 1.27)
					(thickness 0.15)
				)
				(justify left bottom)
				(hide yes)
			)
		)
		(property "License" "Apache-2.0"
			(at 106.68 144.78 0)
			(effects
				(font
					(size 1.27 1.27)
					(thickness 0.15)
				)
				(justify left bottom)
				(hide yes)
			)
		)
		(pin "1"
		)
		(instances
			(project "k410t-devboard"
				(path ""
					(reference "#PWR0215")
					(unit 1)
				)
			)
		)
	)
	(symbol
		(lib_id "antmicroLEDIndicationDiscrete:LED_G_0603_KP-1608CGCK")
		(at 53.34 257.81 0)
		(unit 1)
		(exclude_from_sim no)
		(in_bom yes)
		(on_board yes)
		(dnp no)
		(property "Reference" "D29"
			(at 64.135 255.905 0)
			(effects
				(font
					(size 1.27 1.27)
				)
				(justify right)
			)
		)
		(property "Value" "LED_G_0603_KP-1608CGCK"
			(at 60.96 257.175 0)
			(effects
				(font
					(size 1.27 1.27)
					(thickness 0.15)
				)
				(justify left bottom)
				(hide yes)
			)
		)
		(property "Footprint" "antmicro-footprints:LED_0603_1608Metric_G"
			(at 76.2 267.97 0)
			(effects
				(font
					(size 1.27 1.27)
					(thickness 0.15)
				)
				(justify left bottom)
				(hide yes)
			)
		)
		(property "Datasheet" "http://www.kingbright.com/attachments/file/psearch//000/00/00/KP-1608CGCK(Ver.23B).pdf"
			(at 76.2 270.51 0)
			(effects
				(font
					(size 1.27 1.27)
					(thickness 0.15)
				)
				(justify left bottom)
				(hide yes)
			)
		)
		(property "Description" ""
			(at 53.34 257.81 0)
			(effects
				(font
					(size 1.27 1.27)
				)
			)
		)
		(property "MPN" "KP-1608CGCK"
			(at 76.2 273.05 0)
			(effects
				(font
					(size 1.27 1.27)
					(thickness 0.15)
				)
				(justify left bottom)
				(hide yes)
			)
		)
		(property "Manufacturer" "Kingbright"
			(at 76.2 275.59 0)
			(effects
				(font
					(size 1.27 1.27)
					(thickness 0.15)
				)
				(justify left bottom)
				(hide yes)
			)
		)
		(property "Author" "Antmicro"
			(at 76.2 278.13 0)
			(effects
				(font
					(size 1.27 1.27)
					(thickness 0.15)
				)
				(justify left bottom)
				(hide yes)
			)
		)
		(property "License" "Apache-2.0"
			(at 76.2 280.67 0)
			(effects
				(font
					(size 1.27 1.27)
					(thickness 0.15)
				)
				(justify left bottom)
				(hide yes)
			)
		)
		(property "Color" "Green"
			(at 48.26 256.54 0)
			(effects
				(font
					(size 1.27 1.27)
				)
				(justify left bottom)
			)
		)
		(pin "1"
		)
		(pin "2"
		)
		(instances
			(project "k410t-devboard"
				(path ""
					(reference "D29")
					(unit 1)
				)
			)
		)
	)
	(symbol
		(lib_id "antmicropower:PWR_FLAG")
		(at 125.73 124.46 0)
		(unit 1)
		(exclude_from_sim no)
		(in_bom yes)
		(on_board yes)
		(dnp no)
		(property "Reference" "#FLG07"
			(at 125.73 122.555 0)
			(effects
				(font
					(size 1.27 1.27)
				)
				(hide yes)
			)
		)
		(property "Value" "PWR_FLAG"
			(at 125.73 120.65 0)
			(effects
				(font
					(size 1.27 1.27)
				)
			)
		)
		(property "Footprint" ""
			(at 125.73 124.46 0)
			(effects
				(font
					(size 1.27 1.27)
				)
				(hide yes)
			)
		)
		(property "Datasheet" ""
			(at 125.73 124.46 0)
			(effects
				(font
					(size 1.27 1.27)
				)
				(hide yes)
			)
		)
		(property "Description" ""
			(at 125.73 124.46 0)
			(effects
				(font
					(size 1.27 1.27)
				)
			)
		)
		(pin "1"
		)
		(instances
			(project "k410t-devboard"
				(path ""
					(reference "#FLG07")
					(unit 1)
				)
			)
		)
	)
	(symbol
		(lib_id "antmicroCapacitors0402:C_10u_0402")
		(at 162.56 133.35 90)
		(unit 1)
		(exclude_from_sim no)
		(in_bom yes)
		(on_board yes)
		(dnp no)
		(property "Reference" "C236"
			(at 163.195 128.905 90)
			(effects
				(font
					(size 1.27 1.27)
				)
				(justify right)
			)
		)
		(property "Value" "C_10u_0402"
			(at 172.72 113.03 0)
			(effects
				(font
					(size 1.27 1.27)
					(thickness 0.15)
				)
				(justify left bottom)
				(hide yes)
			)
		)
		(property "Footprint" "antmicro-footprints:C_0402_1005Metric"
			(at 175.26 113.03 0)
			(effects
				(font
					(size 1.27 1.27)
					(thickness 0.15)
				)
				(justify left bottom)
				(hide yes)
			)
		)
		(property "Datasheet" "https://www.yageo.com/en/Chart/Download/pdf/CC0402MRX5R5BB106"
			(at 177.8 113.03 0)
			(effects
				(font
					(size 1.27 1.27)
					(thickness 0.15)
				)
				(justify left bottom)
				(hide yes)
			)
		)
		(property "Description" ""
			(at 162.56 133.35 0)
			(effects
				(font
					(size 1.27 1.27)
				)
			)
		)
		(property "Manufacturer" "YAGEO"
			(at 182.88 113.03 0)
			(effects
				(font
					(size 1.27 1.27)
					(thickness 0.15)
				)
				(justify left bottom)
				(hide yes)
			)
		)
		(property "MPN" "CC0402MRX5R5BB106"
			(at 180.34 113.03 0)
			(effects
				(font
					(size 1.27 1.27)
					(thickness 0.15)
				)
				(justify left bottom)
				(hide yes)
			)
		)
		(property "Val" "10u"
			(at 163.195 132.715 90)
			(effects
				(font
					(size 1.27 1.27)
					(thickness 0.15)
				)
				(justify right)
			)
		)
		(property "License" "Apache-2.0"
			(at 185.42 113.03 0)
			(effects
				(font
					(size 1.27 1.27)
					(thickness 0.15)
				)
				(justify left bottom)
				(hide yes)
			)
		)
		(property "Author" "Antmicro"
			(at 187.96 113.03 0)
			(effects
				(font
					(size 1.27 1.27)
					(thickness 0.15)
				)
				(justify left bottom)
				(hide yes)
			)
		)
		(property "Voltage" ""
			(at 190.5 113.03 0)
			(effects
				(font
					(size 1.27 1.27)
				)
				(justify left bottom)
				(hide yes)
			)
		)
		(property "Dielectric" ""
			(at 193.04 113.03 0)
			(effects
				(font
					(size 1.27 1.27)
				)
				(justify left bottom)
				(hide yes)
			)
		)
		(pin "1"
		)
		(pin "2"
		)
		(instances
			(project "k410t-devboard"
				(path ""
					(reference "C236")
					(unit 1)
				)
			)
		)
	)
	(symbol
		(lib_id "antmicropower:GND")
		(at 331.47 246.38 0)
		(unit 1)
		(exclude_from_sim no)
		(in_bom yes)
		(on_board yes)
		(dnp no)
		(property "Reference" "#PWR0268"
			(at 331.47 252.73 0)
			(effects
				(font
					(size 1.27 1.27)
				)
				(hide yes)
			)
		)
		(property "Value" "GND"
			(at 331.47 250.19 0)
			(effects
				(font
					(size 1.27 1.27)
				)
			)
		)
		(property "Footprint" ""
			(at 340.36 254 0)
			(effects
				(font
					(size 1.27 1.27)
					(thickness 0.15)
				)
				(justify left bottom)
				(hide yes)
			)
		)
		(property "Datasheet" ""
			(at 340.36 259.08 0)
			(effects
				(font
					(size 1.27 1.27)
					(thickness 0.15)
				)
				(justify left bottom)
				(hide yes)
			)
		)
		(property "Description" ""
			(at 331.47 246.38 0)
			(effects
				(font
					(size 1.27 1.27)
				)
			)
		)
		(property "Author" "Antmicro"
			(at 340.36 254 0)
			(effects
				(font
					(size 1.27 1.27)
					(thickness 0.15)
				)
				(justify left bottom)
				(hide yes)
			)
		)
		(property "License" "Apache-2.0"
			(at 340.36 256.54 0)
			(effects
				(font
					(size 1.27 1.27)
					(thickness 0.15)
				)
				(justify left bottom)
				(hide yes)
			)
		)
		(pin "1"
		)
		(instances
			(project "k410t-devboard"
				(path ""
					(reference "#PWR0268")
					(unit 1)
				)
			)
		)
	)
	(symbol
		(lib_id "antmicroCapacitors0402:C_10u_0402")
		(at 104.14 151.13 90)
		(unit 1)
		(exclude_from_sim no)
		(in_bom yes)
		(on_board yes)
		(dnp no)
		(property "Reference" "C225"
			(at 104.775 146.685 90)
			(effects
				(font
					(size 1.27 1.27)
				)
				(justify right)
			)
		)
		(property "Value" "C_10u_0402"
			(at 114.3 130.81 0)
			(effects
				(font
					(size 1.27 1.27)
					(thickness 0.15)
				)
				(justify left bottom)
				(hide yes)
			)
		)
		(property "Footprint" "antmicro-footprints:C_0402_1005Metric"
			(at 116.84 130.81 0)
			(effects
				(font
					(size 1.27 1.27)
					(thickness 0.15)
				)
				(justify left bottom)
				(hide yes)
			)
		)
		(property "Datasheet" "https://www.yageo.com/en/Chart/Download/pdf/CC0402MRX5R5BB106"
			(at 119.38 130.81 0)
			(effects
				(font
					(size 1.27 1.27)
					(thickness 0.15)
				)
				(justify left bottom)
				(hide yes)
			)
		)
		(property "Description" ""
			(at 104.14 151.13 0)
			(effects
				(font
					(size 1.27 1.27)
				)
			)
		)
		(property "Manufacturer" "YAGEO"
			(at 124.46 130.81 0)
			(effects
				(font
					(size 1.27 1.27)
					(thickness 0.15)
				)
				(justify left bottom)
				(hide yes)
			)
		)
		(property "MPN" "CC0402MRX5R5BB106"
			(at 121.92 130.81 0)
			(effects
				(font
					(size 1.27 1.27)
					(thickness 0.15)
				)
				(justify left bottom)
				(hide yes)
			)
		)
		(property "Val" "10u"
			(at 104.775 150.495 90)
			(effects
				(font
					(size 1.27 1.27)
					(thickness 0.15)
				)
				(justify right)
			)
		)
		(property "License" "Apache-2.0"
			(at 127 130.81 0)
			(effects
				(font
					(size 1.27 1.27)
					(thickness 0.15)
				)
				(justify left bottom)
				(hide yes)
			)
		)
		(property "Author" "Antmicro"
			(at 129.54 130.81 0)
			(effects
				(font
					(size 1.27 1.27)
					(thickness 0.15)
				)
				(justify left bottom)
				(hide yes)
			)
		)
		(property "Voltage" ""
			(at 132.08 130.81 0)
			(effects
				(font
					(size 1.27 1.27)
				)
				(justify left bottom)
				(hide yes)
			)
		)
		(property "Dielectric" ""
			(at 134.62 130.81 0)
			(effects
				(font
					(size 1.27 1.27)
				)
				(justify left bottom)
				(hide yes)
			)
		)
		(pin "1"
		)
		(pin "2"
		)
		(instances
			(project "k410t-devboard"
				(path ""
					(reference "C225")
					(unit 1)
				)
			)
		)
	)
	(symbol
		(lib_id "antmicroCapacitors0402:C_100n_0402")
		(at 128.27 175.26 90)
		(unit 1)
		(exclude_from_sim no)
		(in_bom yes)
		(on_board yes)
		(dnp no)
		(property "Reference" "C241"
			(at 128.905 170.815 90)
			(effects
				(font
					(size 1.27 1.27)
				)
				(justify right)
			)
		)
		(property "Value" "C_100n_0402"
			(at 138.43 154.94 0)
			(effects
				(font
					(size 1.27 1.27)
					(thickness 0.15)
				)
				(justify left bottom)
				(hide yes)
			)
		)
		(property "Footprint" "antmicro-footprints:C_0402_1005Metric"
			(at 140.97 154.94 0)
			(effects
				(font
					(size 1.27 1.27)
					(thickness 0.15)
				)
				(justify left bottom)
				(hide yes)
			)
		)
		(property "Datasheet" "https://www.murata.com/products/productdetail?partno=GRM155R61H104KE14%23"
			(at 143.51 154.94 0)
			(effects
				(font
					(size 1.27 1.27)
					(thickness 0.15)
				)
				(justify left bottom)
				(hide yes)
			)
		)
		(property "Description" ""
			(at 128.27 175.26 0)
			(effects
				(font
					(size 1.27 1.27)
				)
			)
		)
		(property "Manufacturer" "Murata"
			(at 148.59 154.94 0)
			(effects
				(font
					(size 1.27 1.27)
					(thickness 0.15)
				)
				(justify left bottom)
				(hide yes)
			)
		)
		(property "MPN" "GRM155R61H104KE14D"
			(at 146.05 154.94 0)
			(effects
				(font
					(size 1.27 1.27)
					(thickness 0.15)
				)
				(justify left bottom)
				(hide yes)
			)
		)
		(property "Val" "100n"
			(at 128.905 174.625 90)
			(effects
				(font
					(size 1.27 1.27)
					(thickness 0.15)
				)
				(justify right)
			)
		)
		(property "License" "Apache-2.0"
			(at 151.13 154.94 0)
			(effects
				(font
					(size 1.27 1.27)
					(thickness 0.15)
				)
				(justify left bottom)
				(hide yes)
			)
		)
		(property "Author" "Antmicro"
			(at 153.67 154.94 0)
			(effects
				(font
					(size 1.27 1.27)
					(thickness 0.15)
				)
				(justify left bottom)
				(hide yes)
			)
		)
		(property "Voltage" "50V"
			(at 156.21 154.94 0)
			(effects
				(font
					(size 1.27 1.27)
				)
				(justify left bottom)
				(hide yes)
			)
		)
		(property "Dielectric" "X5R"
			(at 158.75 154.94 0)
			(effects
				(font
					(size 1.27 1.27)
				)
				(justify left bottom)
				(hide yes)
			)
		)
		(pin "1"
		)
		(pin "2"
		)
		(instances
			(project "k410t-devboard"
				(path ""
					(reference "C241")
					(unit 1)
				)
			)
		)
	)
	(symbol
		(lib_id "antmicroCapacitors0402:C_100n_0402")
		(at 137.16 151.13 90)
		(unit 1)
		(exclude_from_sim no)
		(in_bom yes)
		(on_board yes)
		(dnp no)
		(property "Reference" "C237"
			(at 137.795 146.685 90)
			(effects
				(font
					(size 1.27 1.27)
				)
				(justify right)
			)
		)
		(property "Value" "C_100n_0402"
			(at 147.32 130.81 0)
			(effects
				(font
					(size 1.27 1.27)
					(thickness 0.15)
				)
				(justify left bottom)
				(hide yes)
			)
		)
		(property "Footprint" "antmicro-footprints:C_0402_1005Metric"
			(at 149.86 130.81 0)
			(effects
				(font
					(size 1.27 1.27)
					(thickness 0.15)
				)
				(justify left bottom)
				(hide yes)
			)
		)
		(property "Datasheet" "https://www.murata.com/products/productdetail?partno=GRM155R61H104KE14%23"
			(at 152.4 130.81 0)
			(effects
				(font
					(size 1.27 1.27)
					(thickness 0.15)
				)
				(justify left bottom)
				(hide yes)
			)
		)
		(property "Description" ""
			(at 137.16 151.13 0)
			(effects
				(font
					(size 1.27 1.27)
				)
			)
		)
		(property "Manufacturer" "Murata"
			(at 157.48 130.81 0)
			(effects
				(font
					(size 1.27 1.27)
					(thickness 0.15)
				)
				(justify left bottom)
				(hide yes)
			)
		)
		(property "MPN" "GRM155R61H104KE14D"
			(at 154.94 130.81 0)
			(effects
				(font
					(size 1.27 1.27)
					(thickness 0.15)
				)
				(justify left bottom)
				(hide yes)
			)
		)
		(property "Val" "100n"
			(at 137.795 150.495 90)
			(effects
				(font
					(size 1.27 1.27)
					(thickness 0.15)
				)
				(justify right)
			)
		)
		(property "License" "Apache-2.0"
			(at 160.02 130.81 0)
			(effects
				(font
					(size 1.27 1.27)
					(thickness 0.15)
				)
				(justify left bottom)
				(hide yes)
			)
		)
		(property "Author" "Antmicro"
			(at 162.56 130.81 0)
			(effects
				(font
					(size 1.27 1.27)
					(thickness 0.15)
				)
				(justify left bottom)
				(hide yes)
			)
		)
		(property "Voltage" "50V"
			(at 165.1 130.81 0)
			(effects
				(font
					(size 1.27 1.27)
				)
				(justify left bottom)
				(hide yes)
			)
		)
		(property "Dielectric" "X5R"
			(at 167.64 130.81 0)
			(effects
				(font
					(size 1.27 1.27)
				)
				(justify left bottom)
				(hide yes)
			)
		)
		(pin "1"
		)
		(pin "2"
		)
		(instances
			(project "k410t-devboard"
				(path ""
					(reference "C237")
					(unit 1)
				)
			)
		)
	)
	(symbol
		(lib_id "antmicropower:GND")
		(at 312.42 154.94 0)
		(unit 1)
		(exclude_from_sim no)
		(in_bom yes)
		(on_board yes)
		(dnp no)
		(property "Reference" "#PWR0262"
			(at 312.42 161.29 0)
			(effects
				(font
					(size 1.27 1.27)
				)
				(hide yes)
			)
		)
		(property "Value" "GND"
			(at 312.42 158.75 0)
			(effects
				(font
					(size 1.27 1.27)
				)
			)
		)
		(property "Footprint" ""
			(at 321.31 162.56 0)
			(effects
				(font
					(size 1.27 1.27)
					(thickness 0.15)
				)
				(justify left bottom)
				(hide yes)
			)
		)
		(property "Datasheet" ""
			(at 321.31 167.64 0)
			(effects
				(font
					(size 1.27 1.27)
					(thickness 0.15)
				)
				(justify left bottom)
				(hide yes)
			)
		)
		(property "Description" ""
			(at 312.42 154.94 0)
			(effects
				(font
					(size 1.27 1.27)
				)
			)
		)
		(property "Author" "Antmicro"
			(at 321.31 162.56 0)
			(effects
				(font
					(size 1.27 1.27)
					(thickness 0.15)
				)
				(justify left bottom)
				(hide yes)
			)
		)
		(property "License" "Apache-2.0"
			(at 321.31 165.1 0)
			(effects
				(font
					(size 1.27 1.27)
					(thickness 0.15)
				)
				(justify left bottom)
				(hide yes)
			)
		)
		(pin "1"
		)
		(instances
			(project "k410t-devboard"
				(path ""
					(reference "#PWR0262")
					(unit 1)
				)
			)
		)
	)
	(symbol
		(lib_id "antmicroResistors0402:R_15k_0402")
		(at 288.29 69.85 90)
		(unit 1)
		(exclude_from_sim no)
		(in_bom no)
		(on_board yes)
		(dnp yes)
		(property "Reference" "R170"
			(at 289.56 66.04 90)
			(effects
				(font
					(size 1.27 1.27)
				)
				(justify right)
			)
		)
		(property "Value" "R_15k_0402"
			(at 300.99 49.53 0)
			(effects
				(font
					(size 1.27 1.27)
					(thickness 0.15)
				)
				(justify left bottom)
				(hide yes)
			)
		)
		(property "Footprint" "antmicro-footprints:R_0402_1005Metric"
			(at 303.53 49.53 0)
			(effects
				(font
					(size 1.27 1.27)
					(thickness 0.15)
				)
				(justify left bottom)
				(hide yes)
			)
		)
		(property "Datasheet" "https://www.bourns.com/docs/product-datasheets/cr.pdf"
			(at 306.07 49.53 0)
			(effects
				(font
					(size 1.27 1.27)
					(thickness 0.15)
				)
				(justify left bottom)
				(hide yes)
			)
		)
		(property "Description" ""
			(at 288.29 69.85 0)
			(effects
				(font
					(size 1.27 1.27)
				)
			)
		)
		(property "Manufacturer" "Bourns"
			(at 311.15 49.53 0)
			(effects
				(font
					(size 1.27 1.27)
					(thickness 0.15)
				)
				(justify left bottom)
				(hide yes)
			)
		)
		(property "MPN" "CR0402-FX-1502GLF"
			(at 308.61 49.53 0)
			(effects
				(font
					(size 1.27 1.27)
					(thickness 0.15)
				)
				(justify left bottom)
				(hide yes)
			)
		)
		(property "Val" "15k"
			(at 289.56 68.58 90)
			(effects
				(font
					(size 1.27 1.27)
					(thickness 0.15)
				)
				(justify right)
			)
		)
		(property "DNP" "DNP"
			(at 288.29 65.405 0)
			(effects
				(font
					(size 1.27 1.27)
				)
				(justify right)
			)
		)
		(property "License" "Apache-2.0"
			(at 313.69 49.53 0)
			(effects
				(font
					(size 1.27 1.27)
					(thickness 0.15)
				)
				(justify left bottom)
				(hide yes)
			)
		)
		(property "Author" "Antmicro"
			(at 316.23 49.53 0)
			(effects
				(font
					(size 1.27 1.27)
					(thickness 0.15)
				)
				(justify left bottom)
				(hide yes)
			)
		)
		(property "Tolerance" "1%"
			(at 298.45 49.53 0)
			(effects
				(font
					(size 1.27 1.27)
				)
				(justify left bottom)
				(hide yes)
			)
		)
		(pin "1"
		)
		(pin "2"
		)
		(instances
			(project "k410t-devboard"
				(path ""
					(reference "R170")
					(unit 1)
				)
			)
		)
	)
	(symbol
		(lib_id "antmicropower:GND")
		(at 116.84 96.52 0)
		(unit 1)
		(exclude_from_sim no)
		(in_bom yes)
		(on_board yes)
		(dnp no)
		(property "Reference" "#PWR0217"
			(at 116.84 102.87 0)
			(effects
				(font
					(size 1.27 1.27)
				)
				(hide yes)
			)
		)
		(property "Value" "GND"
			(at 116.84 100.33 0)
			(effects
				(font
					(size 1.27 1.27)
				)
			)
		)
		(property "Footprint" ""
			(at 125.73 104.14 0)
			(effects
				(font
					(size 1.27 1.27)
					(thickness 0.15)
				)
				(justify left bottom)
				(hide yes)
			)
		)
		(property "Datasheet" ""
			(at 125.73 109.22 0)
			(effects
				(font
					(size 1.27 1.27)
					(thickness 0.15)
				)
				(justify left bottom)
				(hide yes)
			)
		)
		(property "Description" ""
			(at 116.84 96.52 0)
			(effects
				(font
					(size 1.27 1.27)
				)
			)
		)
		(property "Author" "Antmicro"
			(at 125.73 104.14 0)
			(effects
				(font
					(size 1.27 1.27)
					(thickness 0.15)
				)
				(justify left bottom)
				(hide yes)
			)
		)
		(property "License" "Apache-2.0"
			(at 125.73 106.68 0)
			(effects
				(font
					(size 1.27 1.27)
					(thickness 0.15)
				)
				(justify left bottom)
				(hide yes)
			)
		)
		(pin "1"
		)
		(instances
			(project "k410t-devboard"
				(path ""
					(reference "#PWR0217")
					(unit 1)
				)
			)
		)
	)
	(symbol
		(lib_id "antmicroCapacitors0402:C_1u_0402")
		(at 149.86 33.02 90)
		(unit 1)
		(exclude_from_sim no)
		(in_bom yes)
		(on_board yes)
		(dnp no)
		(property "Reference" "C226"
			(at 150.495 28.575 90)
			(effects
				(font
					(size 1.27 1.27)
				)
				(justify right)
			)
		)
		(property "Value" "C_1u_0402"
			(at 160.02 12.7 0)
			(effects
				(font
					(size 1.27 1.27)
					(thickness 0.15)
				)
				(justify left bottom)
				(hide yes)
			)
		)
		(property "Footprint" "antmicro-footprints:C_0402_1005Metric"
			(at 162.56 12.7 0)
			(effects
				(font
					(size 1.27 1.27)
					(thickness 0.15)
				)
				(justify left bottom)
				(hide yes)
			)
		)
		(property "Datasheet" "https://product.tdk.com/en/search/capacitor/ceramic/mlcc/info?part_no=C1005X6S1A105K050BC"
			(at 165.1 12.7 0)
			(effects
				(font
					(size 1.27 1.27)
					(thickness 0.15)
				)
				(justify left bottom)
				(hide yes)
			)
		)
		(property "Description" ""
			(at 149.86 33.02 0)
			(effects
				(font
					(size 1.27 1.27)
				)
			)
		)
		(property "Manufacturer" "TDK"
			(at 170.18 12.7 0)
			(effects
				(font
					(size 1.27 1.27)
					(thickness 0.15)
				)
				(justify left bottom)
				(hide yes)
			)
		)
		(property "MPN" "C1005X6S1A105K050BC"
			(at 167.64 12.7 0)
			(effects
				(font
					(size 1.27 1.27)
					(thickness 0.15)
				)
				(justify left bottom)
				(hide yes)
			)
		)
		(property "Val" "1u"
			(at 150.495 32.385 90)
			(effects
				(font
					(size 1.27 1.27)
					(thickness 0.15)
				)
				(justify right)
			)
		)
		(property "License" "Apache-2.0"
			(at 172.72 12.7 0)
			(effects
				(font
					(size 1.27 1.27)
					(thickness 0.15)
				)
				(justify left bottom)
				(hide yes)
			)
		)
		(property "Author" "Antmicro"
			(at 175.26 12.7 0)
			(effects
				(font
					(size 1.27 1.27)
					(thickness 0.15)
				)
				(justify left bottom)
				(hide yes)
			)
		)
		(property "Voltage" ""
			(at 177.8 12.7 0)
			(effects
				(font
					(size 1.27 1.27)
				)
				(justify left bottom)
				(hide yes)
			)
		)
		(property "Dielectric" ""
			(at 180.34 12.7 0)
			(effects
				(font
					(size 1.27 1.27)
				)
				(justify left bottom)
				(hide yes)
			)
		)
		(pin "1"
		)
		(pin "2"
		)
		(instances
			(project "k410t-devboard"
				(path ""
					(reference "C226")
					(unit 1)
				)
			)
		)
	)
	(symbol
		(lib_id "antmicroResistors0402:R_4k7_0402")
		(at 377.19 201.93 270)
		(unit 1)
		(exclude_from_sim no)
		(in_bom yes)
		(on_board yes)
		(dnp no)
		(property "Reference" "R193"
			(at 375.92 203.2 90)
			(effects
				(font
					(size 1.27 1.27)
				)
				(justify right)
			)
		)
		(property "Value" "R_4k7_0402"
			(at 364.49 222.25 0)
			(effects
				(font
					(size 1.27 1.27)
					(thickness 0.15)
				)
				(justify left bottom)
				(hide yes)
			)
		)
		(property "Footprint" "antmicro-footprints:R_0402_1005Metric"
			(at 361.95 222.25 0)
			(effects
				(font
					(size 1.27 1.27)
					(thickness 0.15)
				)
				(justify left bottom)
				(hide yes)
			)
		)
		(property "Datasheet" "https://www.bourns.com/docs/product-datasheets/cr.pdf"
			(at 359.41 222.25 0)
			(effects
				(font
					(size 1.27 1.27)
					(thickness 0.15)
				)
				(justify left bottom)
				(hide yes)
			)
		)
		(property "Description" ""
			(at 377.19 201.93 0)
			(effects
				(font
					(size 1.27 1.27)
				)
			)
		)
		(property "Manufacturer" "Bourns"
			(at 354.33 222.25 0)
			(effects
				(font
					(size 1.27 1.27)
					(thickness 0.15)
				)
				(justify left bottom)
				(hide yes)
			)
		)
		(property "MPN" "CR0402-FX-4701GLF"
			(at 356.87 222.25 0)
			(effects
				(font
					(size 1.27 1.27)
					(thickness 0.15)
				)
				(justify left bottom)
				(hide yes)
			)
		)
		(property "Val" "4k7"
			(at 375.92 205.74 90)
			(effects
				(font
					(size 1.27 1.27)
					(thickness 0.15)
				)
				(justify right)
			)
		)
		(property "License" "Apache-2.0"
			(at 351.79 222.25 0)
			(effects
				(font
					(size 1.27 1.27)
					(thickness 0.15)
				)
				(justify left bottom)
				(hide yes)
			)
		)
		(property "Author" "Antmicro"
			(at 349.25 222.25 0)
			(effects
				(font
					(size 1.27 1.27)
					(thickness 0.15)
				)
				(justify left bottom)
				(hide yes)
			)
		)
		(property "Tolerance" "1%"
			(at 367.03 222.25 0)
			(effects
				(font
					(size 1.27 1.27)
				)
				(justify left bottom)
				(hide yes)
			)
		)
		(pin "1"
		)
		(pin "2"
		)
		(instances
			(project "k410t-devboard"
				(path ""
					(reference "R193")
					(unit 1)
				)
			)
		)
	)
	(symbol
		(lib_id "antmicroResistors0402:R_0R_0402")
		(at 21.59 69.85 270)
		(unit 1)
		(exclude_from_sim no)
		(in_bom no)
		(on_board yes)
		(dnp yes)
		(property "Reference" "R342"
			(at 22.86 71.12 90)
			(effects
				(font
					(size 1.27 1.27)
				)
				(justify left)
			)
		)
		(property "Value" "R_0R_0402"
			(at 8.89 90.17 0)
			(effects
				(font
					(size 1.27 1.27)
					(thickness 0.15)
				)
				(justify left bottom)
				(hide yes)
			)
		)
		(property "Footprint" "antmicro-footprints:R_0402_1005Metric"
			(at 6.35 90.17 0)
			(effects
				(font
					(size 1.27 1.27)
					(thickness 0.15)
				)
				(justify left bottom)
				(hide yes)
			)
		)
		(property "Datasheet" "https://industrial.panasonic.com/cdbs/www-data/pdf/RDA0000/AOA0000C301.pdf"
			(at 3.81 90.17 0)
			(effects
				(font
					(size 1.27 1.27)
					(thickness 0.15)
				)
				(justify left bottom)
				(hide yes)
			)
		)
		(property "Description" ""
			(at 21.59 69.85 0)
			(effects
				(font
					(size 1.27 1.27)
				)
			)
		)
		(property "Manufacturer" "Panasonic"
			(at -1.27 90.17 0)
			(effects
				(font
					(size 1.27 1.27)
					(thickness 0.15)
				)
				(justify left bottom)
				(hide yes)
			)
		)
		(property "MPN" "ERJ2GE0R00X"
			(at 1.27 90.17 0)
			(effects
				(font
					(size 1.27 1.27)
					(thickness 0.15)
				)
				(justify left bottom)
				(hide yes)
			)
		)
		(property "Val" "0R"
			(at 22.86 73.66 90)
			(effects
				(font
					(size 1.27 1.27)
					(thickness 0.15)
				)
				(justify left)
			)
		)
		(property "DNP" "DNP"
			(at 21.59 70.485 0)
			(effects
				(font
					(size 1.27 1.27)
				)
				(justify left)
			)
		)
		(property "License" "Apache-2.0"
			(at -3.81 90.17 0)
			(effects
				(font
					(size 1.27 1.27)
					(thickness 0.15)
				)
				(justify left bottom)
				(hide yes)
			)
		)
		(property "Author" "Antmicro"
			(at -6.35 90.17 0)
			(effects
				(font
					(size 1.27 1.27)
					(thickness 0.15)
				)
				(justify left bottom)
				(hide yes)
			)
		)
		(property "Tolerance" "~"
			(at 11.43 90.17 0)
			(effects
				(font
					(size 1.27 1.27)
				)
				(justify left bottom)
				(hide yes)
			)
		)
		(property "Current" "1A"
			(at 19.05 76.1999 90)
			(effects
				(font
					(size 1.27 1.27)
					(thickness 0.15)
				)
				(justify right)
				(hide yes)
			)
		)
		(pin "1"
		)
		(pin "2"
		)
		(instances
			(project "k410t-devboard"
				(path ""
					(reference "R342")
					(unit 1)
				)
			)
		)
	)
	(symbol
		(lib_id "antmicropower:GND")
		(at 382.27 100.33 0)
		(unit 1)
		(exclude_from_sim no)
		(in_bom yes)
		(on_board yes)
		(dnp no)
		(property "Reference" "#PWR0277"
			(at 382.27 106.68 0)
			(effects
				(font
					(size 1.27 1.27)
				)
				(hide yes)
			)
		)
		(property "Value" "GND"
			(at 382.27 104.14 0)
			(effects
				(font
					(size 1.27 1.27)
				)
			)
		)
		(property "Footprint" ""
			(at 391.16 107.95 0)
			(effects
				(font
					(size 1.27 1.27)
					(thickness 0.15)
				)
				(justify left bottom)
				(hide yes)
			)
		)
		(property "Datasheet" ""
			(at 391.16 113.03 0)
			(effects
				(font
					(size 1.27 1.27)
					(thickness 0.15)
				)
				(justify left bottom)
				(hide yes)
			)
		)
		(property "Description" ""
			(at 382.27 100.33 0)
			(effects
				(font
					(size 1.27 1.27)
				)
			)
		)
		(property "Author" "Antmicro"
			(at 391.16 107.95 0)
			(effects
				(font
					(size 1.27 1.27)
					(thickness 0.15)
				)
				(justify left bottom)
				(hide yes)
			)
		)
		(property "License" "Apache-2.0"
			(at 391.16 110.49 0)
			(effects
				(font
					(size 1.27 1.27)
					(thickness 0.15)
				)
				(justify left bottom)
				(hide yes)
			)
		)
		(pin "1"
		)
		(instances
			(project "k410t-devboard"
				(path ""
					(reference "#PWR0277")
					(unit 1)
				)
			)
		)
	)
	(symbol
		(lib_id "antmicropower:GND")
		(at 270.51 149.86 0)
		(mirror y)
		(unit 1)
		(exclude_from_sim no)
		(in_bom yes)
		(on_board yes)
		(dnp no)
		(property "Reference" "#PWR0248"
			(at 270.51 156.21 0)
			(effects
				(font
					(size 1.27 1.27)
				)
				(hide yes)
			)
		)
		(property "Value" "GND"
			(at 270.51 153.67 0)
			(effects
				(font
					(size 1.27 1.27)
				)
			)
		)
		(property "Footprint" ""
			(at 261.62 157.48 0)
			(effects
				(font
					(size 1.27 1.27)
					(thickness 0.15)
				)
				(justify left bottom)
				(hide yes)
			)
		)
		(property "Datasheet" ""
			(at 261.62 162.56 0)
			(effects
				(font
					(size 1.27 1.27)
					(thickness 0.15)
				)
				(justify left bottom)
				(hide yes)
			)
		)
		(property "Description" ""
			(at 270.51 149.86 0)
			(effects
				(font
					(size 1.27 1.27)
				)
			)
		)
		(property "Author" "Antmicro"
			(at 261.62 157.48 0)
			(effects
				(font
					(size 1.27 1.27)
					(thickness 0.15)
				)
				(justify left bottom)
				(hide yes)
			)
		)
		(property "License" "Apache-2.0"
			(at 261.62 160.02 0)
			(effects
				(font
					(size 1.27 1.27)
					(thickness 0.15)
				)
				(justify left bottom)
				(hide yes)
			)
		)
		(pin "1"
		)
		(instances
			(project "k410t-devboard"
				(path ""
					(reference "#PWR0248")
					(unit 1)
				)
			)
		)
	)
	(symbol
		(lib_id "antmicroResistors0402:R_47k_0402")
		(at 252.73 231.14 90)
		(unit 1)
		(exclude_from_sim no)
		(in_bom yes)
		(on_board yes)
		(dnp no)
		(property "Reference" "R166"
			(at 254 227.33 90)
			(effects
				(font
					(size 1.27 1.27)
				)
				(justify right)
			)
		)
		(property "Value" "R_47k_0402"
			(at 265.43 210.82 0)
			(effects
				(font
					(size 1.27 1.27)
					(thickness 0.15)
				)
				(justify left bottom)
				(hide yes)
			)
		)
		(property "Footprint" "antmicro-footprints:R_0402_1005Metric"
			(at 267.97 210.82 0)
			(effects
				(font
					(size 1.27 1.27)
					(thickness 0.15)
				)
				(justify left bottom)
				(hide yes)
			)
		)
		(property "Datasheet" "https://www.bourns.com/docs/product-datasheets/cr.pdf"
			(at 270.51 210.82 0)
			(effects
				(font
					(size 1.27 1.27)
					(thickness 0.15)
				)
				(justify left bottom)
				(hide yes)
			)
		)
		(property "Description" ""
			(at 252.73 231.14 0)
			(effects
				(font
					(size 1.27 1.27)
				)
			)
		)
		(property "Manufacturer" "Bourns"
			(at 275.59 210.82 0)
			(effects
				(font
					(size 1.27 1.27)
					(thickness 0.15)
				)
				(justify left bottom)
				(hide yes)
			)
		)
		(property "MPN" "CR0402-FX-4702GLF"
			(at 273.05 210.82 0)
			(effects
				(font
					(size 1.27 1.27)
					(thickness 0.15)
				)
				(justify left bottom)
				(hide yes)
			)
		)
		(property "Val" "47k"
			(at 254 229.87 90)
			(effects
				(font
					(size 1.27 1.27)
					(thickness 0.15)
				)
				(justify right)
			)
		)
		(property "License" "Apache-2.0"
			(at 278.13 210.82 0)
			(effects
				(font
					(size 1.27 1.27)
					(thickness 0.15)
				)
				(justify left bottom)
				(hide yes)
			)
		)
		(property "Author" "Antmicro"
			(at 280.67 210.82 0)
			(effects
				(font
					(size 1.27 1.27)
					(thickness 0.15)
				)
				(justify left bottom)
				(hide yes)
			)
		)
		(property "Tolerance" "1%"
			(at 262.89 210.82 0)
			(effects
				(font
					(size 1.27 1.27)
				)
				(justify left bottom)
				(hide yes)
			)
		)
		(pin "1"
		)
		(pin "2"
		)
		(instances
			(project "k410t-devboard"
				(path ""
					(reference "R166")
					(unit 1)
				)
			)
		)
	)
	(symbol
		(lib_id "antmicroCapacitors0402:C_10u_0402")
		(at 104.14 175.26 90)
		(unit 1)
		(exclude_from_sim no)
		(in_bom yes)
		(on_board yes)
		(dnp no)
		(property "Reference" "C234"
			(at 104.775 170.815 90)
			(effects
				(font
					(size 1.27 1.27)
				)
				(justify right)
			)
		)
		(property "Value" "C_10u_0402"
			(at 114.3 154.94 0)
			(effects
				(font
					(size 1.27 1.27)
					(thickness 0.15)
				)
				(justify left bottom)
				(hide yes)
			)
		)
		(property "Footprint" "antmicro-footprints:C_0402_1005Metric"
			(at 116.84 154.94 0)
			(effects
				(font
					(size 1.27 1.27)
					(thickness 0.15)
				)
				(justify left bottom)
				(hide yes)
			)
		)
		(property "Datasheet" "https://www.yageo.com/en/Chart/Download/pdf/CC0402MRX5R5BB106"
			(at 119.38 154.94 0)
			(effects
				(font
					(size 1.27 1.27)
					(thickness 0.15)
				)
				(justify left bottom)
				(hide yes)
			)
		)
		(property "Description" ""
			(at 104.14 175.26 0)
			(effects
				(font
					(size 1.27 1.27)
				)
			)
		)
		(property "Manufacturer" "YAGEO"
			(at 124.46 154.94 0)
			(effects
				(font
					(size 1.27 1.27)
					(thickness 0.15)
				)
				(justify left bottom)
				(hide yes)
			)
		)
		(property "MPN" "CC0402MRX5R5BB106"
			(at 121.92 154.94 0)
			(effects
				(font
					(size 1.27 1.27)
					(thickness 0.15)
				)
				(justify left bottom)
				(hide yes)
			)
		)
		(property "Val" "10u"
			(at 104.775 174.625 90)
			(effects
				(font
					(size 1.27 1.27)
					(thickness 0.15)
				)
				(justify right)
			)
		)
		(property "License" "Apache-2.0"
			(at 127 154.94 0)
			(effects
				(font
					(size 1.27 1.27)
					(thickness 0.15)
				)
				(justify left bottom)
				(hide yes)
			)
		)
		(property "Author" "Antmicro"
			(at 129.54 154.94 0)
			(effects
				(font
					(size 1.27 1.27)
					(thickness 0.15)
				)
				(justify left bottom)
				(hide yes)
			)
		)
		(property "Voltage" ""
			(at 132.08 154.94 0)
			(effects
				(font
					(size 1.27 1.27)
				)
				(justify left bottom)
				(hide yes)
			)
		)
		(property "Dielectric" ""
			(at 134.62 154.94 0)
			(effects
				(font
					(size 1.27 1.27)
				)
				(justify left bottom)
				(hide yes)
			)
		)
		(pin "1"
		)
		(pin "2"
		)
		(instances
			(project "k410t-devboard"
				(path ""
					(reference "C234")
					(unit 1)
				)
			)
		)
	)
	(symbol
		(lib_id "antmicroCapacitors0402:C_100n_0402")
		(at 318.77 31.75 90)
		(unit 1)
		(exclude_from_sim no)
		(in_bom yes)
		(on_board yes)
		(dnp no)
		(property "Reference" "C244"
			(at 319.405 27.305 90)
			(effects
				(font
					(size 1.27 1.27)
				)
				(justify right)
			)
		)
		(property "Value" "C_100n_0402"
			(at 328.93 11.43 0)
			(effects
				(font
					(size 1.27 1.27)
					(thickness 0.15)
				)
				(justify left bottom)
				(hide yes)
			)
		)
		(property "Footprint" "antmicro-footprints:C_0402_1005Metric"
			(at 331.47 11.43 0)
			(effects
				(font
					(size 1.27 1.27)
					(thickness 0.15)
				)
				(justify left bottom)
				(hide yes)
			)
		)
		(property "Datasheet" "https://www.murata.com/products/productdetail?partno=GRM155R61H104KE14%23"
			(at 334.01 11.43 0)
			(effects
				(font
					(size 1.27 1.27)
					(thickness 0.15)
				)
				(justify left bottom)
				(hide yes)
			)
		)
		(property "Description" ""
			(at 318.77 31.75 0)
			(effects
				(font
					(size 1.27 1.27)
				)
			)
		)
		(property "Manufacturer" "Murata"
			(at 339.09 11.43 0)
			(effects
				(font
					(size 1.27 1.27)
					(thickness 0.15)
				)
				(justify left bottom)
				(hide yes)
			)
		)
		(property "MPN" "GRM155R61H104KE14D"
			(at 336.55 11.43 0)
			(effects
				(font
					(size 1.27 1.27)
					(thickness 0.15)
				)
				(justify left bottom)
				(hide yes)
			)
		)
		(property "Val" "100n"
			(at 319.405 31.115 90)
			(effects
				(font
					(size 1.27 1.27)
					(thickness 0.15)
				)
				(justify right)
			)
		)
		(property "License" "Apache-2.0"
			(at 341.63 11.43 0)
			(effects
				(font
					(size 1.27 1.27)
					(thickness 0.15)
				)
				(justify left bottom)
				(hide yes)
			)
		)
		(property "Author" "Antmicro"
			(at 344.17 11.43 0)
			(effects
				(font
					(size 1.27 1.27)
					(thickness 0.15)
				)
				(justify left bottom)
				(hide yes)
			)
		)
		(property "Voltage" "50V"
			(at 346.71 11.43 0)
			(effects
				(font
					(size 1.27 1.27)
				)
				(justify left bottom)
				(hide yes)
			)
		)
		(property "Dielectric" "X5R"
			(at 349.25 11.43 0)
			(effects
				(font
					(size 1.27 1.27)
				)
				(justify left bottom)
				(hide yes)
			)
		)
		(pin "1"
		)
		(pin "2"
		)
		(instances
			(project "k410t-devboard"
				(path ""
					(reference "C244")
					(unit 1)
				)
			)
		)
	)
	(symbol
		(lib_id "antmicroCapacitors0402:C_100n_0402")
		(at 397.51 245.11 90)
		(unit 1)
		(exclude_from_sim no)
		(in_bom yes)
		(on_board yes)
		(dnp no)
		(property "Reference" "C402"
			(at 398.145 240.665 90)
			(effects
				(font
					(size 1.27 1.27)
				)
				(justify right)
			)
		)
		(property "Value" "C_100n_0402"
			(at 407.67 224.79 0)
			(effects
				(font
					(size 1.27 1.27)
					(thickness 0.15)
				)
				(justify left bottom)
				(hide yes)
			)
		)
		(property "Footprint" "antmicro-footprints:C_0402_1005Metric"
			(at 410.21 224.79 0)
			(effects
				(font
					(size 1.27 1.27)
					(thickness 0.15)
				)
				(justify left bottom)
				(hide yes)
			)
		)
		(property "Datasheet" "https://www.murata.com/products/productdetail?partno=GRM155R61H104KE14%23"
			(at 412.75 224.79 0)
			(effects
				(font
					(size 1.27 1.27)
					(thickness 0.15)
				)
				(justify left bottom)
				(hide yes)
			)
		)
		(property "Description" ""
			(at 397.51 245.11 0)
			(effects
				(font
					(size 1.27 1.27)
				)
			)
		)
		(property "Manufacturer" "Murata"
			(at 417.83 224.79 0)
			(effects
				(font
					(size 1.27 1.27)
					(thickness 0.15)
				)
				(justify left bottom)
				(hide yes)
			)
		)
		(property "MPN" "GRM155R61H104KE14D"
			(at 415.29 224.79 0)
			(effects
				(font
					(size 1.27 1.27)
					(thickness 0.15)
				)
				(justify left bottom)
				(hide yes)
			)
		)
		(property "Val" "100n"
			(at 398.145 244.475 90)
			(effects
				(font
					(size 1.27 1.27)
					(thickness 0.15)
				)
				(justify right)
			)
		)
		(property "License" "Apache-2.0"
			(at 420.37 224.79 0)
			(effects
				(font
					(size 1.27 1.27)
					(thickness 0.15)
				)
				(justify left bottom)
				(hide yes)
			)
		)
		(property "Author" "Antmicro"
			(at 422.91 224.79 0)
			(effects
				(font
					(size 1.27 1.27)
					(thickness 0.15)
				)
				(justify left bottom)
				(hide yes)
			)
		)
		(property "Voltage" "50V"
			(at 425.45 224.79 0)
			(effects
				(font
					(size 1.27 1.27)
				)
				(justify left bottom)
				(hide yes)
			)
		)
		(property "Dielectric" "X5R"
			(at 427.99 224.79 0)
			(effects
				(font
					(size 1.27 1.27)
				)
				(justify left bottom)
				(hide yes)
			)
		)
		(pin "1"
		)
		(pin "2"
		)
		(instances
			(project "k410t-devboard"
				(path ""
					(reference "C402")
					(unit 1)
				)
			)
		)
	)
	(symbol
		(lib_id "antmicroCapacitors0402:C_100n_0402")
		(at 355.6 31.75 90)
		(unit 1)
		(exclude_from_sim no)
		(in_bom yes)
		(on_board yes)
		(dnp no)
		(property "Reference" "C246"
			(at 356.235 27.305 90)
			(effects
				(font
					(size 1.27 1.27)
				)
				(justify right)
			)
		)
		(property "Value" "C_100n_0402"
			(at 365.76 11.43 0)
			(effects
				(font
					(size 1.27 1.27)
					(thickness 0.15)
				)
				(justify left bottom)
				(hide yes)
			)
		)
		(property "Footprint" "antmicro-footprints:C_0402_1005Metric"
			(at 368.3 11.43 0)
			(effects
				(font
					(size 1.27 1.27)
					(thickness 0.15)
				)
				(justify left bottom)
				(hide yes)
			)
		)
		(property "Datasheet" "https://www.murata.com/products/productdetail?partno=GRM155R61H104KE14%23"
			(at 370.84 11.43 0)
			(effects
				(font
					(size 1.27 1.27)
					(thickness 0.15)
				)
				(justify left bottom)
				(hide yes)
			)
		)
		(property "Description" ""
			(at 355.6 31.75 0)
			(effects
				(font
					(size 1.27 1.27)
				)
			)
		)
		(property "Manufacturer" "Murata"
			(at 375.92 11.43 0)
			(effects
				(font
					(size 1.27 1.27)
					(thickness 0.15)
				)
				(justify left bottom)
				(hide yes)
			)
		)
		(property "MPN" "GRM155R61H104KE14D"
			(at 373.38 11.43 0)
			(effects
				(font
					(size 1.27 1.27)
					(thickness 0.15)
				)
				(justify left bottom)
				(hide yes)
			)
		)
		(property "Val" "100n"
			(at 356.235 31.115 90)
			(effects
				(font
					(size 1.27 1.27)
					(thickness 0.15)
				)
				(justify right)
			)
		)
		(property "License" "Apache-2.0"
			(at 378.46 11.43 0)
			(effects
				(font
					(size 1.27 1.27)
					(thickness 0.15)
				)
				(justify left bottom)
				(hide yes)
			)
		)
		(property "Author" "Antmicro"
			(at 381 11.43 0)
			(effects
				(font
					(size 1.27 1.27)
					(thickness 0.15)
				)
				(justify left bottom)
				(hide yes)
			)
		)
		(property "Voltage" "50V"
			(at 383.54 11.43 0)
			(effects
				(font
					(size 1.27 1.27)
				)
				(justify left bottom)
				(hide yes)
			)
		)
		(property "Dielectric" "X5R"
			(at 386.08 11.43 0)
			(effects
				(font
					(size 1.27 1.27)
				)
				(justify left bottom)
				(hide yes)
			)
		)
		(pin "1"
		)
		(pin "2"
		)
		(instances
			(project "k410t-devboard"
				(path ""
					(reference "C246")
					(unit 1)
				)
			)
		)
	)
	(symbol
		(lib_id "antmicropower:GND")
		(at 252.73 250.19 0)
		(mirror y)
		(unit 1)
		(exclude_from_sim no)
		(in_bom yes)
		(on_board yes)
		(dnp no)
		(property "Reference" "#PWR0245"
			(at 252.73 256.54 0)
			(effects
				(font
					(size 1.27 1.27)
				)
				(hide yes)
			)
		)
		(property "Value" "GND"
			(at 252.73 254 0)
			(effects
				(font
					(size 1.27 1.27)
				)
			)
		)
		(property "Footprint" ""
			(at 243.84 257.81 0)
			(effects
				(font
					(size 1.27 1.27)
					(thickness 0.15)
				)
				(justify left bottom)
				(hide yes)
			)
		)
		(property "Datasheet" ""
			(at 243.84 262.89 0)
			(effects
				(font
					(size 1.27 1.27)
					(thickness 0.15)
				)
				(justify left bottom)
				(hide yes)
			)
		)
		(property "Description" ""
			(at 252.73 250.19 0)
			(effects
				(font
					(size 1.27 1.27)
				)
			)
		)
		(property "Author" "Antmicro"
			(at 243.84 257.81 0)
			(effects
				(font
					(size 1.27 1.27)
					(thickness 0.15)
				)
				(justify left bottom)
				(hide yes)
			)
		)
		(property "License" "Apache-2.0"
			(at 243.84 260.35 0)
			(effects
				(font
					(size 1.27 1.27)
					(thickness 0.15)
				)
				(justify left bottom)
				(hide yes)
			)
		)
		(pin "1"
		)
		(instances
			(project "k410t-devboard"
				(path ""
					(reference "#PWR0245")
					(unit 1)
				)
			)
		)
	)
	(symbol
		(lib_id "antmicropower:GND")
		(at 321.31 246.38 0)
		(unit 1)
		(exclude_from_sim no)
		(in_bom yes)
		(on_board yes)
		(dnp no)
		(property "Reference" "#PWR0266"
			(at 321.31 252.73 0)
			(effects
				(font
					(size 1.27 1.27)
				)
				(hide yes)
			)
		)
		(property "Value" "GND"
			(at 321.31 250.19 0)
			(effects
				(font
					(size 1.27 1.27)
				)
			)
		)
		(property "Footprint" ""
			(at 330.2 254 0)
			(effects
				(font
					(size 1.27 1.27)
					(thickness 0.15)
				)
				(justify left bottom)
				(hide yes)
			)
		)
		(property "Datasheet" ""
			(at 330.2 259.08 0)
			(effects
				(font
					(size 1.27 1.27)
					(thickness 0.15)
				)
				(justify left bottom)
				(hide yes)
			)
		)
		(property "Description" ""
			(at 321.31 246.38 0)
			(effects
				(font
					(size 1.27 1.27)
				)
			)
		)
		(property "Author" "Antmicro"
			(at 330.2 254 0)
			(effects
				(font
					(size 1.27 1.27)
					(thickness 0.15)
				)
				(justify left bottom)
				(hide yes)
			)
		)
		(property "License" "Apache-2.0"
			(at 330.2 256.54 0)
			(effects
				(font
					(size 1.27 1.27)
					(thickness 0.15)
				)
				(justify left bottom)
				(hide yes)
			)
		)
		(pin "1"
		)
		(instances
			(project "k410t-devboard"
				(path ""
					(reference "#PWR0266")
					(unit 1)
				)
			)
		)
	)
	(symbol
		(lib_id "antmicroResistors0402:R_5k1_0402")
		(at 271.78 50.8 0)
		(unit 1)
		(exclude_from_sim no)
		(in_bom yes)
		(on_board yes)
		(dnp no)
		(property "Reference" "R362"
			(at 279.4 49.53 0)
			(effects
				(font
					(size 1.27 1.27)
				)
			)
		)
		(property "Value" "R_5k1_0402"
			(at 292.1 63.5 0)
			(effects
				(font
					(size 1.27 1.27)
					(thickness 0.15)
				)
				(justify left bottom)
				(hide yes)
			)
		)
		(property "Footprint" "antmicro-footprints:R_0402_1005Metric"
			(at 292.1 66.04 0)
			(effects
				(font
					(size 1.27 1.27)
					(thickness 0.15)
				)
				(justify left bottom)
				(hide yes)
			)
		)
		(property "Datasheet" "https://www.bourns.com/docs/product-datasheets/cr.pdf"
			(at 292.1 68.58 0)
			(effects
				(font
					(size 1.27 1.27)
					(thickness 0.15)
				)
				(justify left bottom)
				(hide yes)
			)
		)
		(property "Description" ""
			(at 271.78 50.8 0)
			(effects
				(font
					(size 1.27 1.27)
				)
			)
		)
		(property "Manufacturer" "Bourns"
			(at 292.1 73.66 0)
			(effects
				(font
					(size 1.27 1.27)
					(thickness 0.15)
				)
				(justify left bottom)
				(hide yes)
			)
		)
		(property "MPN" "CR0402-FX-5101GLF"
			(at 292.1 71.12 0)
			(effects
				(font
					(size 1.27 1.27)
					(thickness 0.15)
				)
				(justify left bottom)
				(hide yes)
			)
		)
		(property "Val" "5k1"
			(at 269.875 49.53 0)
			(effects
				(font
					(size 1.27 1.27)
					(thickness 0.15)
				)
			)
		)
		(property "License" "Apache-2.0"
			(at 292.1 76.2 0)
			(effects
				(font
					(size 1.27 1.27)
					(thickness 0.15)
				)
				(justify left bottom)
				(hide yes)
			)
		)
		(property "Author" "Antmicro"
			(at 292.1 78.74 0)
			(effects
				(font
					(size 1.27 1.27)
					(thickness 0.15)
				)
				(justify left bottom)
				(hide yes)
			)
		)
		(property "Tolerance" "1%"
			(at 292.1 60.96 0)
			(effects
				(font
					(size 1.27 1.27)
				)
				(justify left bottom)
				(hide yes)
			)
		)
		(pin "1"
		)
		(pin "2"
		)
		(instances
			(project "k410t-devboard"
				(path ""
					(reference "R362")
					(unit 1)
				)
			)
		)
	)
	(symbol
		(lib_id "antmicroLEDIndicationDiscrete:LED_G_0603_KP-1608CGCK")
		(at 53.34 251.46 0)
		(unit 1)
		(exclude_from_sim no)
		(in_bom yes)
		(on_board yes)
		(dnp no)
		(property "Reference" "D28"
			(at 64.135 249.555 0)
			(effects
				(font
					(size 1.27 1.27)
				)
				(justify right)
			)
		)
		(property "Value" "LED_G_0603_KP-1608CGCK"
			(at 60.96 250.825 0)
			(effects
				(font
					(size 1.27 1.27)
					(thickness 0.15)
				)
				(justify left bottom)
				(hide yes)
			)
		)
		(property "Footprint" "antmicro-footprints:LED_0603_1608Metric_G"
			(at 76.2 261.62 0)
			(effects
				(font
					(size 1.27 1.27)
					(thickness 0.15)
				)
				(justify left bottom)
				(hide yes)
			)
		)
		(property "Datasheet" "http://www.kingbright.com/attachments/file/psearch//000/00/00/KP-1608CGCK(Ver.23B).pdf"
			(at 76.2 264.16 0)
			(effects
				(font
					(size 1.27 1.27)
					(thickness 0.15)
				)
				(justify left bottom)
				(hide yes)
			)
		)
		(property "Description" ""
			(at 53.34 251.46 0)
			(effects
				(font
					(size 1.27 1.27)
				)
			)
		)
		(property "MPN" "KP-1608CGCK"
			(at 76.2 266.7 0)
			(effects
				(font
					(size 1.27 1.27)
					(thickness 0.15)
				)
				(justify left bottom)
				(hide yes)
			)
		)
		(property "Manufacturer" "Kingbright"
			(at 76.2 269.24 0)
			(effects
				(font
					(size 1.27 1.27)
					(thickness 0.15)
				)
				(justify left bottom)
				(hide yes)
			)
		)
		(property "Author" "Antmicro"
			(at 76.2 271.78 0)
			(effects
				(font
					(size 1.27 1.27)
					(thickness 0.15)
				)
				(justify left bottom)
				(hide yes)
			)
		)
		(property "License" "Apache-2.0"
			(at 76.2 274.32 0)
			(effects
				(font
					(size 1.27 1.27)
					(thickness 0.15)
				)
				(justify left bottom)
				(hide yes)
			)
		)
		(property "Color" "Green"
			(at 48.26 250.19 0)
			(effects
				(font
					(size 1.27 1.27)
				)
				(justify left bottom)
			)
		)
		(pin "1"
		)
		(pin "2"
		)
		(instances
			(project "k410t-devboard"
				(path ""
					(reference "D28")
					(unit 1)
				)
			)
		)
	)
	(symbol
		(lib_id "antmicroResistors0402:R_0R_0402")
		(at 364.49 217.17 180)
		(unit 1)
		(exclude_from_sim no)
		(in_bom yes)
		(on_board yes)
		(dnp no)
		(property "Reference" "R189"
			(at 367.03 215.9 0)
			(effects
				(font
					(size 1.27 1.27)
				)
			)
		)
		(property "Value" "R_0R_0402"
			(at 344.17 204.47 0)
			(effects
				(font
					(size 1.27 1.27)
					(thickness 0.15)
				)
				(justify left bottom)
				(hide yes)
			)
		)
		(property "Footprint" "antmicro-footprints:R_0402_1005Metric"
			(at 344.17 201.93 0)
			(effects
				(font
					(size 1.27 1.27)
					(thickness 0.15)
				)
				(justify left bottom)
				(hide yes)
			)
		)
		(property "Datasheet" "https://industrial.panasonic.com/cdbs/www-data/pdf/RDA0000/AOA0000C301.pdf"
			(at 344.17 199.39 0)
			(effects
				(font
					(size 1.27 1.27)
					(thickness 0.15)
				)
				(justify left bottom)
				(hide yes)
			)
		)
		(property "Description" ""
			(at 364.49 217.17 0)
			(effects
				(font
					(size 1.27 1.27)
				)
			)
		)
		(property "Manufacturer" "Panasonic"
			(at 344.17 194.31 0)
			(effects
				(font
					(size 1.27 1.27)
					(thickness 0.15)
				)
				(justify left bottom)
				(hide yes)
			)
		)
		(property "MPN" "ERJ2GE0R00X"
			(at 344.17 196.85 0)
			(effects
				(font
					(size 1.27 1.27)
					(thickness 0.15)
				)
				(justify left bottom)
				(hide yes)
			)
		)
		(property "Val" "0R"
			(at 358.14 215.9 0)
			(effects
				(font
					(size 1.27 1.27)
					(thickness 0.15)
				)
			)
		)
		(property "License" "Apache-2.0"
			(at 344.17 191.77 0)
			(effects
				(font
					(size 1.27 1.27)
					(thickness 0.15)
				)
				(justify left bottom)
				(hide yes)
			)
		)
		(property "Author" "Antmicro"
			(at 344.17 189.23 0)
			(effects
				(font
					(size 1.27 1.27)
					(thickness 0.15)
				)
				(justify left bottom)
				(hide yes)
			)
		)
		(property "Tolerance" "~"
			(at 344.17 207.01 0)
			(effects
				(font
					(size 1.27 1.27)
				)
				(justify left bottom)
				(hide yes)
			)
		)
		(property "Current" "1A"
			(at 361.95 213.36 0)
			(effects
				(font
					(size 1.27 1.27)
					(thickness 0.15)
				)
				(hide yes)
			)
		)
		(pin "1"
		)
		(pin "2"
		)
		(instances
			(project "k410t-devboard"
				(path ""
					(reference "R189")
					(unit 1)
				)
			)
		)
	)
	(symbol
		(lib_id "antmicropower:GND")
		(at 125.73 153.67 0)
		(unit 1)
		(exclude_from_sim no)
		(in_bom yes)
		(on_board yes)
		(dnp no)
		(property "Reference" "#PWR0221"
			(at 125.73 160.02 0)
			(effects
				(font
					(size 1.27 1.27)
				)
				(hide yes)
			)
		)
		(property "Value" "GND"
			(at 125.73 157.48 0)
			(effects
				(font
					(size 1.27 1.27)
				)
			)
		)
		(property "Footprint" ""
			(at 134.62 161.29 0)
			(effects
				(font
					(size 1.27 1.27)
					(thickness 0.15)
				)
				(justify left bottom)
				(hide yes)
			)
		)
		(property "Datasheet" ""
			(at 134.62 166.37 0)
			(effects
				(font
					(size 1.27 1.27)
					(thickness 0.15)
				)
				(justify left bottom)
				(hide yes)
			)
		)
		(property "Description" ""
			(at 125.73 153.67 0)
			(effects
				(font
					(size 1.27 1.27)
				)
			)
		)
		(property "Author" "Antmicro"
			(at 134.62 161.29 0)
			(effects
				(font
					(size 1.27 1.27)
					(thickness 0.15)
				)
				(justify left bottom)
				(hide yes)
			)
		)
		(property "License" "Apache-2.0"
			(at 134.62 163.83 0)
			(effects
				(font
					(size 1.27 1.27)
					(thickness 0.15)
				)
				(justify left bottom)
				(hide yes)
			)
		)
		(pin "1"
		)
		(instances
			(project "k410t-devboard"
				(path ""
					(reference "#PWR0221")
					(unit 1)
				)
			)
		)
	)
	(symbol
		(lib_id "antmicroResistors0402:R_0R_0402")
		(at 340.36 172.72 0)
		(unit 1)
		(exclude_from_sim no)
		(in_bom yes)
		(on_board yes)
		(dnp no)
		(property "Reference" "R180"
			(at 347.98 171.45 0)
			(effects
				(font
					(size 1.27 1.27)
				)
			)
		)
		(property "Value" "R_0R_0402"
			(at 360.68 185.42 0)
			(effects
				(font
					(size 1.27 1.27)
					(thickness 0.15)
				)
				(justify left bottom)
				(hide yes)
			)
		)
		(property "Footprint" "antmicro-footprints:R_0402_1005Metric"
			(at 360.68 187.96 0)
			(effects
				(font
					(size 1.27 1.27)
					(thickness 0.15)
				)
				(justify left bottom)
				(hide yes)
			)
		)
		(property "Datasheet" "https://industrial.panasonic.com/cdbs/www-data/pdf/RDA0000/AOA0000C301.pdf"
			(at 360.68 190.5 0)
			(effects
				(font
					(size 1.27 1.27)
					(thickness 0.15)
				)
				(justify left bottom)
				(hide yes)
			)
		)
		(property "Description" ""
			(at 340.36 172.72 0)
			(effects
				(font
					(size 1.27 1.27)
				)
			)
		)
		(property "Manufacturer" "Panasonic"
			(at 360.68 195.58 0)
			(effects
				(font
					(size 1.27 1.27)
					(thickness 0.15)
				)
				(justify left bottom)
				(hide yes)
			)
		)
		(property "MPN" "ERJ2GE0R00X"
			(at 360.68 193.04 0)
			(effects
				(font
					(size 1.27 1.27)
					(thickness 0.15)
				)
				(justify left bottom)
				(hide yes)
			)
		)
		(property "Val" "0R"
			(at 339.09 171.45 0)
			(effects
				(font
					(size 1.27 1.27)
					(thickness 0.15)
				)
			)
		)
		(property "License" "Apache-2.0"
			(at 360.68 198.12 0)
			(effects
				(font
					(size 1.27 1.27)
					(thickness 0.15)
				)
				(justify left bottom)
				(hide yes)
			)
		)
		(property "Author" "Antmicro"
			(at 360.68 200.66 0)
			(effects
				(font
					(size 1.27 1.27)
					(thickness 0.15)
				)
				(justify left bottom)
				(hide yes)
			)
		)
		(property "Tolerance" "~"
			(at 360.68 182.88 0)
			(effects
				(font
					(size 1.27 1.27)
				)
				(justify left bottom)
				(hide yes)
			)
		)
		(property "Current" "1A"
			(at 342.9 168.91 0)
			(effects
				(font
					(size 1.27 1.27)
					(thickness 0.15)
				)
				(hide yes)
			)
		)
		(pin "1"
		)
		(pin "2"
		)
		(instances
			(project "k410t-devboard"
				(path ""
					(reference "R180")
					(unit 1)
				)
			)
		)
	)
	(symbol
		(lib_id "antmicropower:GND")
		(at 160.02 218.44 0)
		(unit 1)
		(exclude_from_sim no)
		(in_bom yes)
		(on_board yes)
		(dnp no)
		(property "Reference" "#PWR0234"
			(at 160.02 224.79 0)
			(effects
				(font
					(size 1.27 1.27)
				)
				(hide yes)
			)
		)
		(property "Value" "GND"
			(at 160.02 222.25 0)
			(effects
				(font
					(size 1.27 1.27)
				)
			)
		)
		(property "Footprint" ""
			(at 168.91 226.06 0)
			(effects
				(font
					(size 1.27 1.27)
					(thickness 0.15)
				)
				(justify left bottom)
				(hide yes)
			)
		)
		(property "Datasheet" ""
			(at 168.91 231.14 0)
			(effects
				(font
					(size 1.27 1.27)
					(thickness 0.15)
				)
				(justify left bottom)
				(hide yes)
			)
		)
		(property "Description" ""
			(at 160.02 218.44 0)
			(effects
				(font
					(size 1.27 1.27)
				)
			)
		)
		(property "Author" "Antmicro"
			(at 168.91 226.06 0)
			(effects
				(font
					(size 1.27 1.27)
					(thickness 0.15)
				)
				(justify left bottom)
				(hide yes)
			)
		)
		(property "License" "Apache-2.0"
			(at 168.91 228.6 0)
			(effects
				(font
					(size 1.27 1.27)
					(thickness 0.15)
				)
				(justify left bottom)
				(hide yes)
			)
		)
		(pin "1"
		)
		(instances
			(project "k410t-devboard"
				(path ""
					(reference "#PWR0234")
					(unit 1)
				)
			)
		)
	)
	(symbol
		(lib_id "antmicroCapacitors0402:C_22p_0402")
		(at 160.02 215.9 90)
		(unit 1)
		(exclude_from_sim no)
		(in_bom yes)
		(on_board yes)
		(dnp no)
		(property "Reference" "C235"
			(at 160.655 211.455 90)
			(effects
				(font
					(size 1.27 1.27)
				)
				(justify right)
			)
		)
		(property "Value" "C_22p_0402"
			(at 170.18 195.58 0)
			(effects
				(font
					(size 1.27 1.27)
					(thickness 0.15)
				)
				(justify left bottom)
				(hide yes)
			)
		)
		(property "Footprint" "antmicro-footprints:C_0402_1005Metric"
			(at 172.72 195.58 0)
			(effects
				(font
					(size 1.27 1.27)
					(thickness 0.15)
				)
				(justify left bottom)
				(hide yes)
			)
		)
		(property "Datasheet" "https://www.yageo.com/en/Chart/Download/pdf/CC0402JRNPO9BN220"
			(at 175.26 195.58 0)
			(effects
				(font
					(size 1.27 1.27)
					(thickness 0.15)
				)
				(justify left bottom)
				(hide yes)
			)
		)
		(property "Description" ""
			(at 160.02 215.9 0)
			(effects
				(font
					(size 1.27 1.27)
				)
			)
		)
		(property "Manufacturer" "YAGEO"
			(at 180.34 195.58 0)
			(effects
				(font
					(size 1.27 1.27)
					(thickness 0.15)
				)
				(justify left bottom)
				(hide yes)
			)
		)
		(property "MPN" "CC0402JRNPO9BN220"
			(at 177.8 195.58 0)
			(effects
				(font
					(size 1.27 1.27)
					(thickness 0.15)
				)
				(justify left bottom)
				(hide yes)
			)
		)
		(property "Val" "22p"
			(at 160.655 215.265 90)
			(effects
				(font
					(size 1.27 1.27)
					(thickness 0.15)
				)
				(justify right)
			)
		)
		(property "License" "Apache-2.0"
			(at 182.88 195.58 0)
			(effects
				(font
					(size 1.27 1.27)
					(thickness 0.15)
				)
				(justify left bottom)
				(hide yes)
			)
		)
		(property "Author" "Antmicro"
			(at 185.42 195.58 0)
			(effects
				(font
					(size 1.27 1.27)
					(thickness 0.15)
				)
				(justify left bottom)
				(hide yes)
			)
		)
		(property "Voltage" ""
			(at 187.96 195.58 0)
			(effects
				(font
					(size 1.27 1.27)
				)
				(justify left bottom)
				(hide yes)
			)
		)
		(property "Dielectric" ""
			(at 190.5 195.58 0)
			(effects
				(font
					(size 1.27 1.27)
				)
				(justify left bottom)
				(hide yes)
			)
		)
		(pin "1"
		)
		(pin "2"
		)
		(instances
			(project "k410t-devboard"
				(path ""
					(reference "C235")
					(unit 1)
				)
			)
		)
	)
	(symbol
		(lib_id "antmicroResistors0402:R_10k_0402")
		(at 360.68 95.25 270)
		(unit 1)
		(exclude_from_sim no)
		(in_bom yes)
		(on_board yes)
		(dnp no)
		(property "Reference" "R350"
			(at 361.95 96.52 90)
			(effects
				(font
					(size 1.27 1.27)
				)
				(justify left)
			)
		)
		(property "Value" "R_10k_0402"
			(at 347.98 115.57 0)
			(effects
				(font
					(size 1.27 1.27)
					(thickness 0.15)
				)
				(justify left bottom)
				(hide yes)
			)
		)
		(property "Footprint" "antmicro-footprints:R_0402_1005Metric"
			(at 345.44 115.57 0)
			(effects
				(font
					(size 1.27 1.27)
					(thickness 0.15)
				)
				(justify left bottom)
				(hide yes)
			)
		)
		(property "Datasheet" "https://www.bourns.com/docs/product-datasheets/cr.pdf"
			(at 342.9 115.57 0)
			(effects
				(font
					(size 1.27 1.27)
					(thickness 0.15)
				)
				(justify left bottom)
				(hide yes)
			)
		)
		(property "Description" ""
			(at 360.68 95.25 0)
			(effects
				(font
					(size 1.27 1.27)
				)
			)
		)
		(property "Manufacturer" "Bourns"
			(at 337.82 115.57 0)
			(effects
				(font
					(size 1.27 1.27)
					(thickness 0.15)
				)
				(justify left bottom)
				(hide yes)
			)
		)
		(property "MPN" "CR0402-FX-1002GLF"
			(at 340.36 115.57 0)
			(effects
				(font
					(size 1.27 1.27)
					(thickness 0.15)
				)
				(justify left bottom)
				(hide yes)
			)
		)
		(property "Val" "10k"
			(at 361.95 99.06 90)
			(effects
				(font
					(size 1.27 1.27)
					(thickness 0.15)
				)
				(justify left)
			)
		)
		(property "License" "Apache-2.0"
			(at 335.28 115.57 0)
			(effects
				(font
					(size 1.27 1.27)
					(thickness 0.15)
				)
				(justify left bottom)
				(hide yes)
			)
		)
		(property "Author" "Antmicro"
			(at 332.74 115.57 0)
			(effects
				(font
					(size 1.27 1.27)
					(thickness 0.15)
				)
				(justify left bottom)
				(hide yes)
			)
		)
		(property "Tolerance" "1%"
			(at 350.52 115.57 0)
			(effects
				(font
					(size 1.27 1.27)
				)
				(justify left bottom)
				(hide yes)
			)
		)
		(pin "1"
		)
		(pin "2"
		)
		(instances
			(project "k410t-devboard"
				(path ""
					(reference "R350")
					(unit 1)
				)
			)
		)
	)
	(symbol
		(lib_id "antmicroCapacitors0402:C_100n_0402")
		(at 115.57 151.13 90)
		(unit 1)
		(exclude_from_sim no)
		(in_bom yes)
		(on_board yes)
		(dnp no)
		(property "Reference" "C230"
			(at 116.205 146.685 90)
			(effects
				(font
					(size 1.27 1.27)
				)
				(justify right)
			)
		)
		(property "Value" "C_100n_0402"
			(at 125.73 130.81 0)
			(effects
				(font
					(size 1.27 1.27)
					(thickness 0.15)
				)
				(justify left bottom)
				(hide yes)
			)
		)
		(property "Footprint" "antmicro-footprints:C_0402_1005Metric"
			(at 128.27 130.81 0)
			(effects
				(font
					(size 1.27 1.27)
					(thickness 0.15)
				)
				(justify left bottom)
				(hide yes)
			)
		)
		(property "Datasheet" "https://www.murata.com/products/productdetail?partno=GRM155R61H104KE14%23"
			(at 130.81 130.81 0)
			(effects
				(font
					(size 1.27 1.27)
					(thickness 0.15)
				)
				(justify left bottom)
				(hide yes)
			)
		)
		(property "Description" ""
			(at 115.57 151.13 0)
			(effects
				(font
					(size 1.27 1.27)
				)
			)
		)
		(property "Manufacturer" "Murata"
			(at 135.89 130.81 0)
			(effects
				(font
					(size 1.27 1.27)
					(thickness 0.15)
				)
				(justify left bottom)
				(hide yes)
			)
		)
		(property "MPN" "GRM155R61H104KE14D"
			(at 133.35 130.81 0)
			(effects
				(font
					(size 1.27 1.27)
					(thickness 0.15)
				)
				(justify left bottom)
				(hide yes)
			)
		)
		(property "Val" "100n"
			(at 116.205 150.495 90)
			(effects
				(font
					(size 1.27 1.27)
					(thickness 0.15)
				)
				(justify right)
			)
		)
		(property "License" "Apache-2.0"
			(at 138.43 130.81 0)
			(effects
				(font
					(size 1.27 1.27)
					(thickness 0.15)
				)
				(justify left bottom)
				(hide yes)
			)
		)
		(property "Author" "Antmicro"
			(at 140.97 130.81 0)
			(effects
				(font
					(size 1.27 1.27)
					(thickness 0.15)
				)
				(justify left bottom)
				(hide yes)
			)
		)
		(property "Voltage" "50V"
			(at 143.51 130.81 0)
			(effects
				(font
					(size 1.27 1.27)
				)
				(justify left bottom)
				(hide yes)
			)
		)
		(property "Dielectric" "X5R"
			(at 146.05 130.81 0)
			(effects
				(font
					(size 1.27 1.27)
				)
				(justify left bottom)
				(hide yes)
			)
		)
		(pin "1"
		)
		(pin "2"
		)
		(instances
			(project "k410t-devboard"
				(path ""
					(reference "C230")
					(unit 1)
				)
			)
		)
	)
	(symbol
		(lib_id "antmicroResistors0402:R_33R_0402")
		(at 340.36 177.8 0)
		(unit 1)
		(exclude_from_sim no)
		(in_bom yes)
		(on_board yes)
		(dnp no)
		(property "Reference" "R182"
			(at 347.98 176.53 0)
			(effects
				(font
					(size 1.27 1.27)
				)
			)
		)
		(property "Value" "R_33R_0402"
			(at 360.68 190.5 0)
			(effects
				(font
					(size 1.27 1.27)
					(thickness 0.15)
				)
				(justify left bottom)
				(hide yes)
			)
		)
		(property "Footprint" "antmicro-footprints:R_0402_1005Metric"
			(at 360.68 193.04 0)
			(effects
				(font
					(size 1.27 1.27)
					(thickness 0.15)
				)
				(justify left bottom)
				(hide yes)
			)
		)
		(property "Datasheet" "https://www.bourns.com/docs/product-datasheets/cr.pdf"
			(at 360.68 195.58 0)
			(effects
				(font
					(size 1.27 1.27)
					(thickness 0.15)
				)
				(justify left bottom)
				(hide yes)
			)
		)
		(property "Description" ""
			(at 340.36 177.8 0)
			(effects
				(font
					(size 1.27 1.27)
				)
			)
		)
		(property "Manufacturer" "Bourns"
			(at 360.68 200.66 0)
			(effects
				(font
					(size 1.27 1.27)
					(thickness 0.15)
				)
				(justify left bottom)
				(hide yes)
			)
		)
		(property "MPN" "CR0402-FX-33R0GLF"
			(at 360.68 198.12 0)
			(effects
				(font
					(size 1.27 1.27)
					(thickness 0.15)
				)
				(justify left bottom)
				(hide yes)
			)
		)
		(property "Val" "33R"
			(at 338.455 176.53 0)
			(effects
				(font
					(size 1.27 1.27)
					(thickness 0.15)
				)
			)
		)
		(property "License" "Apache-2.0"
			(at 360.68 203.2 0)
			(effects
				(font
					(size 1.27 1.27)
					(thickness 0.15)
				)
				(justify left bottom)
				(hide yes)
			)
		)
		(property "Author" "Antmicro"
			(at 360.68 205.74 0)
			(effects
				(font
					(size 1.27 1.27)
					(thickness 0.15)
				)
				(justify left bottom)
				(hide yes)
			)
		)
		(property "Tolerance" "1%"
			(at 360.68 187.96 0)
			(effects
				(font
					(size 1.27 1.27)
				)
				(justify left bottom)
				(hide yes)
			)
		)
		(pin "1"
		)
		(pin "2"
		)
		(instances
			(project "k410t-devboard"
				(path ""
					(reference "R182")
					(unit 1)
				)
			)
		)
	)
	(symbol
		(lib_id "antmicropower:GND")
		(at 397.51 246.38 0)
		(unit 1)
		(exclude_from_sim no)
		(in_bom yes)
		(on_board yes)
		(dnp no)
		(property "Reference" "#PWR0281"
			(at 397.51 252.73 0)
			(effects
				(font
					(size 1.27 1.27)
				)
				(hide yes)
			)
		)
		(property "Value" "GND"
			(at 397.51 250.19 0)
			(effects
				(font
					(size 1.27 1.27)
				)
			)
		)
		(property "Footprint" ""
			(at 406.4 254 0)
			(effects
				(font
					(size 1.27 1.27)
					(thickness 0.15)
				)
				(justify left bottom)
				(hide yes)
			)
		)
		(property "Datasheet" ""
			(at 406.4 259.08 0)
			(effects
				(font
					(size 1.27 1.27)
					(thickness 0.15)
				)
				(justify left bottom)
				(hide yes)
			)
		)
		(property "Description" ""
			(at 397.51 246.38 0)
			(effects
				(font
					(size 1.27 1.27)
				)
			)
		)
		(property "Author" "Antmicro"
			(at 406.4 254 0)
			(effects
				(font
					(size 1.27 1.27)
					(thickness 0.15)
				)
				(justify left bottom)
				(hide yes)
			)
		)
		(property "License" "Apache-2.0"
			(at 406.4 256.54 0)
			(effects
				(font
					(size 1.27 1.27)
					(thickness 0.15)
				)
				(justify left bottom)
				(hide yes)
			)
		)
		(pin "1"
		)
		(instances
			(project "k410t-devboard"
				(path ""
					(reference "#PWR0281")
					(unit 1)
				)
			)
		)
	)
	(symbol
		(lib_id "antmicropower:GND")
		(at 287.02 73.66 0)
		(unit 1)
		(exclude_from_sim no)
		(in_bom yes)
		(on_board yes)
		(dnp no)
		(property "Reference" "#PWR0257"
			(at 287.02 80.01 0)
			(effects
				(font
					(size 1.27 1.27)
				)
				(hide yes)
			)
		)
		(property "Value" "GND"
			(at 288.925 77.47 0)
			(effects
				(font
					(size 1.27 1.27)
				)
				(justify right)
			)
		)
		(property "Footprint" ""
			(at 295.91 81.28 0)
			(effects
				(font
					(size 1.27 1.27)
					(thickness 0.15)
				)
				(justify left bottom)
				(hide yes)
			)
		)
		(property "Datasheet" ""
			(at 295.91 86.36 0)
			(effects
				(font
					(size 1.27 1.27)
					(thickness 0.15)
				)
				(justify left bottom)
				(hide yes)
			)
		)
		(property "Description" ""
			(at 287.02 73.66 0)
			(effects
				(font
					(size 1.27 1.27)
				)
			)
		)
		(property "Author" "Antmicro"
			(at 295.91 81.28 0)
			(effects
				(font
					(size 1.27 1.27)
					(thickness 0.15)
				)
				(justify left bottom)
				(hide yes)
			)
		)
		(property "License" "Apache-2.0"
			(at 295.91 83.82 0)
			(effects
				(font
					(size 1.27 1.27)
					(thickness 0.15)
				)
				(justify left bottom)
				(hide yes)
			)
		)
		(pin "1"
		)
		(instances
			(project "k410t-devboard"
				(path ""
					(reference "#PWR0257")
					(unit 1)
				)
			)
		)
	)
	(symbol
		(lib_id "antmicroCapacitors0603:C_10u_25V_0603")
		(at 30.48 140.97 90)
		(unit 1)
		(exclude_from_sim no)
		(in_bom yes)
		(on_board yes)
		(dnp no)
		(property "Reference" "C218"
			(at 31.115 136.525 90)
			(effects
				(font
					(size 1.27 1.27)
				)
				(justify right)
			)
		)
		(property "Value" "C_10u_25V_0603"
			(at 40.64 120.65 0)
			(effects
				(font
					(size 1.27 1.27)
					(thickness 0.15)
				)
				(justify left bottom)
				(hide yes)
			)
		)
		(property "Footprint" "antmicro-footprints:C_0603_1608Metric"
			(at 43.18 120.65 0)
			(effects
				(font
					(size 1.27 1.27)
					(thickness 0.15)
				)
				(justify left bottom)
				(hide yes)
			)
		)
		(property "Datasheet" "https://product.tdk.com/en/search/capacitor/ceramic/mlcc/info?part_no=C1608X5R1E106M080AC"
			(at 45.72 120.65 0)
			(effects
				(font
					(size 1.27 1.27)
					(thickness 0.15)
				)
				(justify left bottom)
				(hide yes)
			)
		)
		(property "Description" ""
			(at 30.48 140.97 0)
			(effects
				(font
					(size 1.27 1.27)
				)
			)
		)
		(property "Manufacturer" "TDK"
			(at 50.8 120.65 0)
			(effects
				(font
					(size 1.27 1.27)
					(thickness 0.15)
				)
				(justify left bottom)
				(hide yes)
			)
		)
		(property "MPN" "C1608X5R1E106M080AC"
			(at 48.26 120.65 0)
			(effects
				(font
					(size 1.27 1.27)
					(thickness 0.15)
				)
				(justify left bottom)
				(hide yes)
			)
		)
		(property "Val" "10u"
			(at 31.115 140.335 90)
			(effects
				(font
					(size 1.27 1.27)
					(thickness 0.15)
				)
				(justify right)
			)
		)
		(property "License" "Apache-2.0"
			(at 53.34 120.65 0)
			(effects
				(font
					(size 1.27 1.27)
					(thickness 0.15)
				)
				(justify left bottom)
				(hide yes)
			)
		)
		(property "Author" "Antmicro"
			(at 55.88 120.65 0)
			(effects
				(font
					(size 1.27 1.27)
					(thickness 0.15)
				)
				(justify left bottom)
				(hide yes)
			)
		)
		(property "Voltage" "25V"
			(at 58.42 120.65 0)
			(effects
				(font
					(size 1.27 1.27)
				)
				(justify left bottom)
				(hide yes)
			)
		)
		(property "Dielectric" ""
			(at 60.96 120.65 0)
			(effects
				(font
					(size 1.27 1.27)
				)
				(justify left bottom)
				(hide yes)
			)
		)
		(pin "1"
		)
		(pin "2"
		)
		(instances
			(project "k410t-devboard"
				(path ""
					(reference "C218")
					(unit 1)
				)
			)
		)
	)
	(symbol
		(lib_id "antmicropower:GND")
		(at 400.05 100.33 0)
		(unit 1)
		(exclude_from_sim no)
		(in_bom yes)
		(on_board yes)
		(dnp no)
		(property "Reference" "#PWR0282"
			(at 400.05 106.68 0)
			(effects
				(font
					(size 1.27 1.27)
				)
				(hide yes)
			)
		)
		(property "Value" "GND"
			(at 400.05 104.14 0)
			(effects
				(font
					(size 1.27 1.27)
				)
			)
		)
		(property "Footprint" ""
			(at 408.94 107.95 0)
			(effects
				(font
					(size 1.27 1.27)
					(thickness 0.15)
				)
				(justify left bottom)
				(hide yes)
			)
		)
		(property "Datasheet" ""
			(at 408.94 113.03 0)
			(effects
				(font
					(size 1.27 1.27)
					(thickness 0.15)
				)
				(justify left bottom)
				(hide yes)
			)
		)
		(property "Description" ""
			(at 400.05 100.33 0)
			(effects
				(font
					(size 1.27 1.27)
				)
			)
		)
		(property "Author" "Antmicro"
			(at 408.94 107.95 0)
			(effects
				(font
					(size 1.27 1.27)
					(thickness 0.15)
				)
				(justify left bottom)
				(hide yes)
			)
		)
		(property "License" "Apache-2.0"
			(at 408.94 110.49 0)
			(effects
				(font
					(size 1.27 1.27)
					(thickness 0.15)
				)
				(justify left bottom)
				(hide yes)
			)
		)
		(pin "1"
		)
		(instances
			(project "k410t-devboard"
				(path ""
					(reference "#PWR0282")
					(unit 1)
				)
			)
		)
	)
	(symbol
		(lib_id "antmicroPMICPowerDistributionSwitchesLoadDrivers:AP22615A_TSOT26")
		(at 361.95 86.36 0)
		(unit 1)
		(exclude_from_sim no)
		(in_bom yes)
		(on_board yes)
		(dnp no)
		(fields_autoplaced yes)
		(property "Reference" "U43"
			(at 369.57 78.74 0)
			(effects
				(font
					(size 1.27 1.27)
				)
			)
		)
		(property "Value" "AP22615A_TSOT26"
			(at 369.57 82.55 0)
			(effects
				(font
					(size 1.27 1.27)
					(thickness 0.15)
				)
				(hide yes)
			)
		)
		(property "Footprint" "antmicro-footprints:TSOT23-6"
			(at 392.43 93.98 0)
			(effects
				(font
					(size 1.27 1.27)
					(thickness 0.15)
				)
				(justify left bottom)
				(hide yes)
			)
		)
		(property "Datasheet" "https://www.mouser.com/datasheet/2/115/DIOD_S_A0008958405_1-2543193.pdf"
			(at 392.43 96.52 0)
			(effects
				(font
					(size 1.27 1.27)
					(thickness 0.15)
				)
				(justify left bottom)
				(hide yes)
			)
		)
		(property "Description" ""
			(at 361.95 86.36 0)
			(effects
				(font
					(size 1.27 1.27)
				)
			)
		)
		(property "MPN" "AP22615AWU-7"
			(at 369.57 81.28 0)
			(effects
				(font
					(size 1.27 1.27)
					(thickness 0.15)
				)
			)
		)
		(property "Manufacturer" "Diodes Incorporated"
			(at 392.43 101.6 0)
			(effects
				(font
					(size 1.27 1.27)
					(thickness 0.15)
				)
				(justify left bottom)
				(hide yes)
			)
		)
		(property "Author" "Antmicro"
			(at 392.43 104.14 0)
			(effects
				(font
					(size 1.27 1.27)
					(thickness 0.15)
				)
				(justify left bottom)
				(hide yes)
			)
		)
		(property "License" "Apache-2.0"
			(at 392.43 106.68 0)
			(effects
				(font
					(size 1.27 1.27)
					(thickness 0.15)
				)
				(justify left bottom)
				(hide yes)
			)
		)
		(pin "1"
		)
		(pin "2"
		)
		(pin "3"
		)
		(pin "4"
		)
		(pin "5"
		)
		(pin "6"
		)
		(instances
			(project "k410t-devboard"
				(path ""
					(reference "U43")
					(unit 1)
				)
			)
		)
	)
	(symbol
		(lib_id "antmicroCapacitors0402:C_100n_0402")
		(at 365.76 245.11 90)
		(unit 1)
		(exclude_from_sim no)
		(in_bom yes)
		(on_board yes)
		(dnp no)
		(property "Reference" "C249"
			(at 366.395 240.665 90)
			(effects
				(font
					(size 1.27 1.27)
				)
				(justify right)
			)
		)
		(property "Value" "C_100n_0402"
			(at 375.92 224.79 0)
			(effects
				(font
					(size 1.27 1.27)
					(thickness 0.15)
				)
				(justify left bottom)
				(hide yes)
			)
		)
		(property "Footprint" "antmicro-footprints:C_0402_1005Metric"
			(at 378.46 224.79 0)
			(effects
				(font
					(size 1.27 1.27)
					(thickness 0.15)
				)
				(justify left bottom)
				(hide yes)
			)
		)
		(property "Datasheet" "https://www.murata.com/products/productdetail?partno=GRM155R61H104KE14%23"
			(at 381 224.79 0)
			(effects
				(font
					(size 1.27 1.27)
					(thickness 0.15)
				)
				(justify left bottom)
				(hide yes)
			)
		)
		(property "Description" ""
			(at 365.76 245.11 0)
			(effects
				(font
					(size 1.27 1.27)
				)
			)
		)
		(property "Manufacturer" "Murata"
			(at 386.08 224.79 0)
			(effects
				(font
					(size 1.27 1.27)
					(thickness 0.15)
				)
				(justify left bottom)
				(hide yes)
			)
		)
		(property "MPN" "GRM155R61H104KE14D"
			(at 383.54 224.79 0)
			(effects
				(font
					(size 1.27 1.27)
					(thickness 0.15)
				)
				(justify left bottom)
				(hide yes)
			)
		)
		(property "Val" "100n"
			(at 366.395 244.475 90)
			(effects
				(font
					(size 1.27 1.27)
					(thickness 0.15)
				)
				(justify right)
			)
		)
		(property "License" "Apache-2.0"
			(at 388.62 224.79 0)
			(effects
				(font
					(size 1.27 1.27)
					(thickness 0.15)
				)
				(justify left bottom)
				(hide yes)
			)
		)
		(property "Author" "Antmicro"
			(at 391.16 224.79 0)
			(effects
				(font
					(size 1.27 1.27)
					(thickness 0.15)
				)
				(justify left bottom)
				(hide yes)
			)
		)
		(property "Voltage" "50V"
			(at 393.7 224.79 0)
			(effects
				(font
					(size 1.27 1.27)
				)
				(justify left bottom)
				(hide yes)
			)
		)
		(property "Dielectric" "X5R"
			(at 396.24 224.79 0)
			(effects
				(font
					(size 1.27 1.27)
				)
				(justify left bottom)
				(hide yes)
			)
		)
		(pin "1"
		)
		(pin "2"
		)
		(instances
			(project "k410t-devboard"
				(path ""
					(reference "C249")
					(unit 1)
				)
			)
		)
	)
	(symbol
		(lib_id "antmicroCapacitors0402:C_100n_0402")
		(at 125.73 151.13 90)
		(unit 1)
		(exclude_from_sim no)
		(in_bom yes)
		(on_board yes)
		(dnp no)
		(property "Reference" "C233"
			(at 126.365 146.685 90)
			(effects
				(font
					(size 1.27 1.27)
				)
				(justify right)
			)
		)
		(property "Value" "C_100n_0402"
			(at 135.89 130.81 0)
			(effects
				(font
					(size 1.27 1.27)
					(thickness 0.15)
				)
				(justify left bottom)
				(hide yes)
			)
		)
		(property "Footprint" "antmicro-footprints:C_0402_1005Metric"
			(at 138.43 130.81 0)
			(effects
				(font
					(size 1.27 1.27)
					(thickness 0.15)
				)
				(justify left bottom)
				(hide yes)
			)
		)
		(property "Datasheet" "https://www.murata.com/products/productdetail?partno=GRM155R61H104KE14%23"
			(at 140.97 130.81 0)
			(effects
				(font
					(size 1.27 1.27)
					(thickness 0.15)
				)
				(justify left bottom)
				(hide yes)
			)
		)
		(property "Description" ""
			(at 125.73 151.13 0)
			(effects
				(font
					(size 1.27 1.27)
				)
			)
		)
		(property "Manufacturer" "Murata"
			(at 146.05 130.81 0)
			(effects
				(font
					(size 1.27 1.27)
					(thickness 0.15)
				)
				(justify left bottom)
				(hide yes)
			)
		)
		(property "MPN" "GRM155R61H104KE14D"
			(at 143.51 130.81 0)
			(effects
				(font
					(size 1.27 1.27)
					(thickness 0.15)
				)
				(justify left bottom)
				(hide yes)
			)
		)
		(property "Val" "100n"
			(at 126.365 150.495 90)
			(effects
				(font
					(size 1.27 1.27)
					(thickness 0.15)
				)
				(justify right)
			)
		)
		(property "License" "Apache-2.0"
			(at 148.59 130.81 0)
			(effects
				(font
					(size 1.27 1.27)
					(thickness 0.15)
				)
				(justify left bottom)
				(hide yes)
			)
		)
		(property "Author" "Antmicro"
			(at 151.13 130.81 0)
			(effects
				(font
					(size 1.27 1.27)
					(thickness 0.15)
				)
				(justify left bottom)
				(hide yes)
			)
		)
		(property "Voltage" "50V"
			(at 153.67 130.81 0)
			(effects
				(font
					(size 1.27 1.27)
				)
				(justify left bottom)
				(hide yes)
			)
		)
		(property "Dielectric" "X5R"
			(at 156.21 130.81 0)
			(effects
				(font
					(size 1.27 1.27)
				)
				(justify left bottom)
				(hide yes)
			)
		)
		(pin "1"
		)
		(pin "2"
		)
		(instances
			(project "k410t-devboard"
				(path ""
					(reference "C233")
					(unit 1)
				)
			)
		)
	)
	(symbol
		(lib_id "antmicroPMICPowerDistributionSwitchesLoadDrivers:AP22615A_TSOT26")
		(at 58.42 82.55 0)
		(unit 1)
		(exclude_from_sim no)
		(in_bom yes)
		(on_board yes)
		(dnp no)
		(fields_autoplaced yes)
		(property "Reference" "U30"
			(at 66.04 74.93 0)
			(effects
				(font
					(size 1.27 1.27)
				)
			)
		)
		(property "Value" "AP22615A_TSOT26"
			(at 66.04 78.74 0)
			(effects
				(font
					(size 1.27 1.27)
					(thickness 0.15)
				)
				(hide yes)
			)
		)
		(property "Footprint" "antmicro-footprints:TSOT23-6"
			(at 88.9 90.17 0)
			(effects
				(font
					(size 1.27 1.27)
					(thickness 0.15)
				)
				(justify left bottom)
				(hide yes)
			)
		)
		(property "Datasheet" "https://www.mouser.com/datasheet/2/115/DIOD_S_A0008958405_1-2543193.pdf"
			(at 88.9 92.71 0)
			(effects
				(font
					(size 1.27 1.27)
					(thickness 0.15)
				)
				(justify left bottom)
				(hide yes)
			)
		)
		(property "Description" ""
			(at 58.42 82.55 0)
			(effects
				(font
					(size 1.27 1.27)
				)
			)
		)
		(property "MPN" "AP22615AWU-7"
			(at 66.04 77.47 0)
			(effects
				(font
					(size 1.27 1.27)
					(thickness 0.15)
				)
			)
		)
		(property "Manufacturer" "Diodes Incorporated"
			(at 88.9 97.79 0)
			(effects
				(font
					(size 1.27 1.27)
					(thickness 0.15)
				)
				(justify left bottom)
				(hide yes)
			)
		)
		(property "Author" "Antmicro"
			(at 88.9 100.33 0)
			(effects
				(font
					(size 1.27 1.27)
					(thickness 0.15)
				)
				(justify left bottom)
				(hide yes)
			)
		)
		(property "License" "Apache-2.0"
			(at 88.9 102.87 0)
			(effects
				(font
					(size 1.27 1.27)
					(thickness 0.15)
				)
				(justify left bottom)
				(hide yes)
			)
		)
		(pin "1"
		)
		(pin "2"
		)
		(pin "3"
		)
		(pin "4"
		)
		(pin "5"
		)
		(pin "6"
		)
		(instances
			(project "k410t-devboard"
				(path ""
					(reference "U30")
					(unit 1)
				)
			)
		)
	)
	(symbol
		(lib_id "antmicropower:GND")
		(at 88.9 96.52 0)
		(unit 1)
		(exclude_from_sim no)
		(in_bom yes)
		(on_board yes)
		(dnp no)
		(property "Reference" "#PWR0210"
			(at 88.9 102.87 0)
			(effects
				(font
					(size 1.27 1.27)
				)
				(hide yes)
			)
		)
		(property "Value" "GND"
			(at 88.9 100.33 0)
			(effects
				(font
					(size 1.27 1.27)
				)
			)
		)
		(property "Footprint" ""
			(at 97.79 104.14 0)
			(effects
				(font
					(size 1.27 1.27)
					(thickness 0.15)
				)
				(justify left bottom)
				(hide yes)
			)
		)
		(property "Datasheet" ""
			(at 97.79 109.22 0)
			(effects
				(font
					(size 1.27 1.27)
					(thickness 0.15)
				)
				(justify left bottom)
				(hide yes)
			)
		)
		(property "Description" ""
			(at 88.9 96.52 0)
			(effects
				(font
					(size 1.27 1.27)
				)
			)
		)
		(property "Author" "Antmicro"
			(at 97.79 104.14 0)
			(effects
				(font
					(size 1.27 1.27)
					(thickness 0.15)
				)
				(justify left bottom)
				(hide yes)
			)
		)
		(property "License" "Apache-2.0"
			(at 97.79 106.68 0)
			(effects
				(font
					(size 1.27 1.27)
					(thickness 0.15)
				)
				(justify left bottom)
				(hide yes)
			)
		)
		(pin "1"
		)
		(instances
			(project "k410t-devboard"
				(path ""
					(reference "#PWR0210")
					(unit 1)
				)
			)
		)
	)
	(symbol
		(lib_id "antmicropower:GND")
		(at 149.86 35.56 0)
		(unit 1)
		(exclude_from_sim no)
		(in_bom yes)
		(on_board yes)
		(dnp no)
		(fields_autoplaced yes)
		(property "Reference" "#PWR0231"
			(at 149.86 41.91 0)
			(effects
				(font
					(size 1.27 1.27)
				)
				(hide yes)
			)
		)
		(property "Value" "GND"
			(at 149.86 40.005 0)
			(effects
				(font
					(size 1.27 1.27)
				)
			)
		)
		(property "Footprint" ""
			(at 158.75 43.18 0)
			(effects
				(font
					(size 1.27 1.27)
					(thickness 0.15)
				)
				(justify left bottom)
				(hide yes)
			)
		)
		(property "Datasheet" ""
			(at 158.75 48.26 0)
			(effects
				(font
					(size 1.27 1.27)
					(thickness 0.15)
				)
				(justify left bottom)
				(hide yes)
			)
		)
		(property "Description" ""
			(at 149.86 35.56 0)
			(effects
				(font
					(size 1.27 1.27)
				)
			)
		)
		(property "Author" "Antmicro"
			(at 158.75 43.18 0)
			(effects
				(font
					(size 1.27 1.27)
					(thickness 0.15)
				)
				(justify left bottom)
				(hide yes)
			)
		)
		(property "License" "Apache-2.0"
			(at 158.75 45.72 0)
			(effects
				(font
					(size 1.27 1.27)
					(thickness 0.15)
				)
				(justify left bottom)
				(hide yes)
			)
		)
		(pin "1"
		)
		(instances
			(project "k410t-devboard"
				(path ""
					(reference "#PWR0231")
					(unit 1)
				)
			)
		)
	)
	(symbol
		(lib_id "antmicropower:PWR_FLAG")
		(at 96.52 81.28 0)
		(unit 1)
		(exclude_from_sim no)
		(in_bom yes)
		(on_board yes)
		(dnp no)
		(property "Reference" "#FLG03"
			(at 96.52 79.375 0)
			(effects
				(font
					(size 1.27 1.27)
				)
				(hide yes)
			)
		)
		(property "Value" "PWR_FLAG"
			(at 96.52 77.47 0)
			(effects
				(font
					(size 1.27 1.27)
				)
			)
		)
		(property "Footprint" ""
			(at 96.52 81.28 0)
			(effects
				(font
					(size 1.27 1.27)
				)
				(hide yes)
			)
		)
		(property "Datasheet" ""
			(at 96.52 81.28 0)
			(effects
				(font
					(size 1.27 1.27)
				)
				(hide yes)
			)
		)
		(property "Description" ""
			(at 96.52 81.28 0)
			(effects
				(font
					(size 1.27 1.27)
				)
			)
		)
		(pin "1"
		)
		(instances
			(project "k410t-devboard"
				(path ""
					(reference "#FLG03")
					(unit 1)
				)
			)
		)
	)
	(symbol
		(lib_id "antmicropower:GND")
		(at 147.32 153.67 0)
		(unit 1)
		(exclude_from_sim no)
		(in_bom yes)
		(on_board yes)
		(dnp no)
		(property "Reference" "#PWR0230"
			(at 147.32 160.02 0)
			(effects
				(font
					(size 1.27 1.27)
				)
				(hide yes)
			)
		)
		(property "Value" "GND"
			(at 147.32 157.48 0)
			(effects
				(font
					(size 1.27 1.27)
				)
			)
		)
		(property "Footprint" ""
			(at 156.21 161.29 0)
			(effects
				(font
					(size 1.27 1.27)
					(thickness 0.15)
				)
				(justify left bottom)
				(hide yes)
			)
		)
		(property "Datasheet" ""
			(at 156.21 166.37 0)
			(effects
				(font
					(size 1.27 1.27)
					(thickness 0.15)
				)
				(justify left bottom)
				(hide yes)
			)
		)
		(property "Description" ""
			(at 147.32 153.67 0)
			(effects
				(font
					(size 1.27 1.27)
				)
			)
		)
		(property "Author" "Antmicro"
			(at 156.21 161.29 0)
			(effects
				(font
					(size 1.27 1.27)
					(thickness 0.15)
				)
				(justify left bottom)
				(hide yes)
			)
		)
		(property "License" "Apache-2.0"
			(at 156.21 163.83 0)
			(effects
				(font
					(size 1.27 1.27)
					(thickness 0.15)
				)
				(justify left bottom)
				(hide yes)
			)
		)
		(pin "1"
		)
		(instances
			(project "k410t-devboard"
				(path ""
					(reference "#PWR0230")
					(unit 1)
				)
			)
		)
	)
	(symbol
		(lib_id "antmicroInterfaceControllers:MAX3421EETJ+")
		(at 166.37 38.1 0)
		(unit 1)
		(exclude_from_sim no)
		(in_bom yes)
		(on_board yes)
		(dnp no)
		(fields_autoplaced yes)
		(property "Reference" "U19"
			(at 180.34 30.48 0)
			(effects
				(font
					(size 1.27 1.27)
				)
			)
		)
		(property "Value" "MAX3421EETJ+"
			(at 180.34 34.29 0)
			(effects
				(font
					(size 1.27 1.27)
					(thickness 0.15)
				)
				(hide yes)
			)
		)
		(property "Footprint" "antmicro-footprints:QFN-32-1EP_5x5mm"
			(at 207.01 48.26 0)
			(effects
				(font
					(size 1.27 1.27)
					(thickness 0.15)
				)
				(justify left bottom)
				(hide yes)
			)
		)
		(property "Datasheet" "https://www.analog.com/media/en/technical-documentation/data-sheets/max3421e.pdf"
			(at 207.01 50.8 0)
			(effects
				(font
					(size 1.27 1.27)
					(thickness 0.15)
				)
				(justify left bottom)
				(hide yes)
			)
		)
		(property "Description" ""
			(at 166.37 38.1 0)
			(effects
				(font
					(size 1.27 1.27)
				)
			)
		)
		(property "MPN" "MAX3421EETJ+"
			(at 180.34 33.02 0)
			(effects
				(font
					(size 1.27 1.27)
					(thickness 0.15)
				)
			)
		)
		(property "Manufacturer" "Maxim Integrated Products"
			(at 207.01 55.88 0)
			(effects
				(font
					(size 1.27 1.27)
					(thickness 0.15)
				)
				(justify left bottom)
				(hide yes)
			)
		)
		(property "Author" "Antmicro"
			(at 207.01 58.42 0)
			(effects
				(font
					(size 1.27 1.27)
					(thickness 0.15)
				)
				(justify left bottom)
				(hide yes)
			)
		)
		(property "License" "Apache-2.0"
			(at 207.01 60.96 0)
			(effects
				(font
					(size 1.27 1.27)
					(thickness 0.15)
				)
				(justify left bottom)
				(hide yes)
			)
		)
		(pin "1"
		)
		(pin "10"
		)
		(pin "11"
		)
		(pin "12"
		)
		(pin "13"
		)
		(pin "14"
		)
		(pin "15"
		)
		(pin "16"
		)
		(pin "17"
		)
		(pin "18"
		)
		(pin "19"
		)
		(pin "2"
		)
		(pin "20"
		)
		(pin "21"
		)
		(pin "22"
		)
		(pin "23"
		)
		(pin "24"
		)
		(pin "25"
		)
		(pin "26"
		)
		(pin "27"
		)
		(pin "28"
		)
		(pin "29"
		)
		(pin "3"
		)
		(pin "30"
		)
		(pin "31"
		)
		(pin "32"
		)
		(pin "33"
		)
		(pin "4"
		)
		(pin "5"
		)
		(pin "6"
		)
		(pin "7"
		)
		(pin "8"
		)
		(pin "9"
		)
		(instances
			(project "k410t-devboard"
				(path ""
					(reference "U19")
					(unit 1)
				)
			)
		)
	)
	(symbol
		(lib_id "antmicropower:GND")
		(at 46.99 77.47 0)
		(unit 1)
		(exclude_from_sim no)
		(in_bom yes)
		(on_board yes)
		(dnp no)
		(property "Reference" "#PWR0201"
			(at 46.99 83.82 0)
			(effects
				(font
					(size 1.27 1.27)
				)
				(hide yes)
			)
		)
		(property "Value" "GND"
			(at 48.895 81.28 0)
			(effects
				(font
					(size 1.27 1.27)
				)
				(justify right)
			)
		)
		(property "Footprint" ""
			(at 55.88 85.09 0)
			(effects
				(font
					(size 1.27 1.27)
					(thickness 0.15)
				)
				(justify left bottom)
				(hide yes)
			)
		)
		(property "Datasheet" ""
			(at 55.88 90.17 0)
			(effects
				(font
					(size 1.27 1.27)
					(thickness 0.15)
				)
				(justify left bottom)
				(hide yes)
			)
		)
		(property "Description" ""
			(at 46.99 77.47 0)
			(effects
				(font
					(size 1.27 1.27)
				)
			)
		)
		(property "Author" "Antmicro"
			(at 55.88 85.09 0)
			(effects
				(font
					(size 1.27 1.27)
					(thickness 0.15)
				)
				(justify left bottom)
				(hide yes)
			)
		)
		(property "License" "Apache-2.0"
			(at 55.88 87.63 0)
			(effects
				(font
					(size 1.27 1.27)
					(thickness 0.15)
				)
				(justify left bottom)
				(hide yes)
			)
		)
		(pin "1"
		)
		(instances
			(project "k410t-devboard"
				(path ""
					(reference "#PWR0201")
					(unit 1)
				)
			)
		)
	)
	(symbol
		(lib_id "antmicropower:GND")
		(at 312.42 222.25 0)
		(unit 1)
		(exclude_from_sim no)
		(in_bom yes)
		(on_board yes)
		(dnp no)
		(property "Reference" "#PWR0264"
			(at 312.42 228.6 0)
			(effects
				(font
					(size 1.27 1.27)
				)
				(hide yes)
			)
		)
		(property "Value" "GND"
			(at 312.42 226.06 0)
			(effects
				(font
					(size 1.27 1.27)
				)
			)
		)
		(property "Footprint" ""
			(at 321.31 229.87 0)
			(effects
				(font
					(size 1.27 1.27)
					(thickness 0.15)
				)
				(justify left bottom)
				(hide yes)
			)
		)
		(property "Datasheet" ""
			(at 321.31 234.95 0)
			(effects
				(font
					(size 1.27 1.27)
					(thickness 0.15)
				)
				(justify left bottom)
				(hide yes)
			)
		)
		(property "Description" ""
			(at 312.42 222.25 0)
			(effects
				(font
					(size 1.27 1.27)
				)
			)
		)
		(property "Author" "Antmicro"
			(at 321.31 229.87 0)
			(effects
				(font
					(size 1.27 1.27)
					(thickness 0.15)
				)
				(justify left bottom)
				(hide yes)
			)
		)
		(property "License" "Apache-2.0"
			(at 321.31 232.41 0)
			(effects
				(font
					(size 1.27 1.27)
					(thickness 0.15)
				)
				(justify left bottom)
				(hide yes)
			)
		)
		(pin "1"
		)
		(instances
			(project "k410t-devboard"
				(path ""
					(reference "#PWR0264")
					(unit 1)
				)
			)
		)
	)
	(symbol
		(lib_id "antmicroResistors0402:R_0R_0402")
		(at 345.44 175.26 180)
		(unit 1)
		(exclude_from_sim no)
		(in_bom no)
		(on_board yes)
		(dnp yes)
		(property "Reference" "R181"
			(at 347.98 173.99 0)
			(effects
				(font
					(size 1.27 1.27)
				)
			)
		)
		(property "Value" "R_0R_0402"
			(at 325.12 162.56 0)
			(effects
				(font
					(size 1.27 1.27)
					(thickness 0.15)
				)
				(justify left bottom)
				(hide yes)
			)
		)
		(property "Footprint" "antmicro-footprints:R_0402_1005Metric"
			(at 325.12 160.02 0)
			(effects
				(font
					(size 1.27 1.27)
					(thickness 0.15)
				)
				(justify left bottom)
				(hide yes)
			)
		)
		(property "Datasheet" "https://industrial.panasonic.com/cdbs/www-data/pdf/RDA0000/AOA0000C301.pdf"
			(at 325.12 157.48 0)
			(effects
				(font
					(size 1.27 1.27)
					(thickness 0.15)
				)
				(justify left bottom)
				(hide yes)
			)
		)
		(property "Description" ""
			(at 345.44 175.26 0)
			(effects
				(font
					(size 1.27 1.27)
				)
			)
		)
		(property "Manufacturer" "Panasonic"
			(at 325.12 152.4 0)
			(effects
				(font
					(size 1.27 1.27)
					(thickness 0.15)
				)
				(justify left bottom)
				(hide yes)
			)
		)
		(property "MPN" "ERJ2GE0R00X"
			(at 325.12 154.94 0)
			(effects
				(font
					(size 1.27 1.27)
					(thickness 0.15)
				)
				(justify left bottom)
				(hide yes)
			)
		)
		(property "Val" "0R"
			(at 339.09 173.99 0)
			(effects
				(font
					(size 1.27 1.27)
					(thickness 0.15)
				)
			)
		)
		(property "DNP" "DNP"
			(at 342.9 175.26 0)
			(effects
				(font
					(size 1.27 1.27)
				)
			)
		)
		(property "License" "Apache-2.0"
			(at 325.12 149.86 0)
			(effects
				(font
					(size 1.27 1.27)
					(thickness 0.15)
				)
				(justify left bottom)
				(hide yes)
			)
		)
		(property "Author" "Antmicro"
			(at 325.12 147.32 0)
			(effects
				(font
					(size 1.27 1.27)
					(thickness 0.15)
				)
				(justify left bottom)
				(hide yes)
			)
		)
		(property "Tolerance" "~"
			(at 325.12 165.1 0)
			(effects
				(font
					(size 1.27 1.27)
				)
				(justify left bottom)
				(hide yes)
			)
		)
		(property "Current" "1A"
			(at 342.9 186.69 0)
			(effects
				(font
					(size 1.27 1.27)
					(thickness 0.15)
				)
				(hide yes)
			)
		)
		(pin "1"
		)
		(pin "2"
		)
		(instances
			(project "k410t-devboard"
				(path ""
					(reference "R181")
					(unit 1)
				)
			)
		)
	)
	(symbol
		(lib_id "antmicroCapacitors0402:C_22p_0402")
		(at 140.97 215.9 90)
		(unit 1)
		(exclude_from_sim no)
		(in_bom yes)
		(on_board yes)
		(dnp no)
		(property "Reference" "C228"
			(at 141.605 211.455 90)
			(effects
				(font
					(size 1.27 1.27)
				)
				(justify right)
			)
		)
		(property "Value" "C_22p_0402"
			(at 151.13 195.58 0)
			(effects
				(font
					(size 1.27 1.27)
					(thickness 0.15)
				)
				(justify left bottom)
				(hide yes)
			)
		)
		(property "Footprint" "antmicro-footprints:C_0402_1005Metric"
			(at 153.67 195.58 0)
			(effects
				(font
					(size 1.27 1.27)
					(thickness 0.15)
				)
				(justify left bottom)
				(hide yes)
			)
		)
		(property "Datasheet" "https://www.yageo.com/en/Chart/Download/pdf/CC0402JRNPO9BN220"
			(at 156.21 195.58 0)
			(effects
				(font
					(size 1.27 1.27)
					(thickness 0.15)
				)
				(justify left bottom)
				(hide yes)
			)
		)
		(property "Description" ""
			(at 140.97 215.9 0)
			(effects
				(font
					(size 1.27 1.27)
				)
			)
		)
		(property "Manufacturer" "YAGEO"
			(at 161.29 195.58 0)
			(effects
				(font
					(size 1.27 1.27)
					(thickness 0.15)
				)
				(justify left bottom)
				(hide yes)
			)
		)
		(property "MPN" "CC0402JRNPO9BN220"
			(at 158.75 195.58 0)
			(effects
				(font
					(size 1.27 1.27)
					(thickness 0.15)
				)
				(justify left bottom)
				(hide yes)
			)
		)
		(property "Val" "22p"
			(at 141.605 215.265 90)
			(effects
				(font
					(size 1.27 1.27)
					(thickness 0.15)
				)
				(justify right)
			)
		)
		(property "License" "Apache-2.0"
			(at 163.83 195.58 0)
			(effects
				(font
					(size 1.27 1.27)
					(thickness 0.15)
				)
				(justify left bottom)
				(hide yes)
			)
		)
		(property "Author" "Antmicro"
			(at 166.37 195.58 0)
			(effects
				(font
					(size 1.27 1.27)
					(thickness 0.15)
				)
				(justify left bottom)
				(hide yes)
			)
		)
		(property "Voltage" ""
			(at 168.91 195.58 0)
			(effects
				(font
					(size 1.27 1.27)
				)
				(justify left bottom)
				(hide yes)
			)
		)
		(property "Dielectric" ""
			(at 171.45 195.58 0)
			(effects
				(font
					(size 1.27 1.27)
				)
				(justify left bottom)
				(hide yes)
			)
		)
		(pin "1"
		)
		(pin "2"
		)
		(instances
			(project "k410t-devboard"
				(path ""
					(reference "C228")
					(unit 1)
				)
			)
		)
	)
	(symbol
		(lib_id "antmicropower:GND")
		(at 96.52 96.52 0)
		(unit 1)
		(exclude_from_sim no)
		(in_bom yes)
		(on_board yes)
		(dnp no)
		(property "Reference" "#PWR0211"
			(at 96.52 102.87 0)
			(effects
				(font
					(size 1.27 1.27)
				)
				(hide yes)
			)
		)
		(property "Value" "GND"
			(at 96.52 100.33 0)
			(effects
				(font
					(size 1.27 1.27)
				)
			)
		)
		(property "Footprint" ""
			(at 105.41 104.14 0)
			(effects
				(font
					(size 1.27 1.27)
					(thickness 0.15)
				)
				(justify left bottom)
				(hide yes)
			)
		)
		(property "Datasheet" ""
			(at 105.41 109.22 0)
			(effects
				(font
					(size 1.27 1.27)
					(thickness 0.15)
				)
				(justify left bottom)
				(hide yes)
			)
		)
		(property "Description" ""
			(at 96.52 96.52 0)
			(effects
				(font
					(size 1.27 1.27)
				)
			)
		)
		(property "Author" "Antmicro"
			(at 105.41 104.14 0)
			(effects
				(font
					(size 1.27 1.27)
					(thickness 0.15)
				)
				(justify left bottom)
				(hide yes)
			)
		)
		(property "License" "Apache-2.0"
			(at 105.41 106.68 0)
			(effects
				(font
					(size 1.27 1.27)
					(thickness 0.15)
				)
				(justify left bottom)
				(hide yes)
			)
		)
		(pin "1"
		)
		(instances
			(project "k410t-devboard"
				(path ""
					(reference "#PWR0211")
					(unit 1)
				)
			)
		)
	)
	(symbol
		(lib_id "antmicroCapacitors0402:C_10u_0402")
		(at 96.52 91.44 90)
		(unit 1)
		(exclude_from_sim no)
		(in_bom yes)
		(on_board yes)
		(dnp no)
		(property "Reference" "C219"
			(at 97.155 86.995 90)
			(effects
				(font
					(size 1.27 1.27)
				)
				(justify right)
			)
		)
		(property "Value" "C_10u_0402"
			(at 106.68 71.12 0)
			(effects
				(font
					(size 1.27 1.27)
					(thickness 0.15)
				)
				(justify left bottom)
				(hide yes)
			)
		)
		(property "Footprint" "antmicro-footprints:C_0402_1005Metric"
			(at 109.22 71.12 0)
			(effects
				(font
					(size 1.27 1.27)
					(thickness 0.15)
				)
				(justify left bottom)
				(hide yes)
			)
		)
		(property "Datasheet" "https://www.yageo.com/en/Chart/Download/pdf/CC0402MRX5R5BB106"
			(at 111.76 71.12 0)
			(effects
				(font
					(size 1.27 1.27)
					(thickness 0.15)
				)
				(justify left bottom)
				(hide yes)
			)
		)
		(property "Description" ""
			(at 96.52 91.44 0)
			(effects
				(font
					(size 1.27 1.27)
				)
			)
		)
		(property "Manufacturer" "YAGEO"
			(at 116.84 71.12 0)
			(effects
				(font
					(size 1.27 1.27)
					(thickness 0.15)
				)
				(justify left bottom)
				(hide yes)
			)
		)
		(property "MPN" "CC0402MRX5R5BB106"
			(at 114.3 71.12 0)
			(effects
				(font
					(size 1.27 1.27)
					(thickness 0.15)
				)
				(justify left bottom)
				(hide yes)
			)
		)
		(property "Val" "10u"
			(at 97.155 90.805 90)
			(effects
				(font
					(size 1.27 1.27)
					(thickness 0.15)
				)
				(justify right)
			)
		)
		(property "License" "Apache-2.0"
			(at 119.38 71.12 0)
			(effects
				(font
					(size 1.27 1.27)
					(thickness 0.15)
				)
				(justify left bottom)
				(hide yes)
			)
		)
		(property "Author" "Antmicro"
			(at 121.92 71.12 0)
			(effects
				(font
					(size 1.27 1.27)
					(thickness 0.15)
				)
				(justify left bottom)
				(hide yes)
			)
		)
		(property "Voltage" ""
			(at 124.46 71.12 0)
			(effects
				(font
					(size 1.27 1.27)
				)
				(justify left bottom)
				(hide yes)
			)
		)
		(property "Dielectric" ""
			(at 127 71.12 0)
			(effects
				(font
					(size 1.27 1.27)
				)
				(justify left bottom)
				(hide yes)
			)
		)
		(pin "1"
		)
		(pin "2"
		)
		(instances
			(project "k410t-devboard"
				(path ""
					(reference "C219")
					(unit 1)
				)
			)
		)
	)
	(symbol
		(lib_id "antmicroResistors0402:R_0R_0402")
		(at 345.44 205.74 0)
		(unit 1)
		(exclude_from_sim no)
		(in_bom yes)
		(on_board yes)
		(dnp no)
		(property "Reference" "R186"
			(at 353.06 204.47 0)
			(effects
				(font
					(size 1.27 1.27)
				)
			)
		)
		(property "Value" "R_0R_0402"
			(at 365.76 218.44 0)
			(effects
				(font
					(size 1.27 1.27)
					(thickness 0.15)
				)
				(justify left bottom)
				(hide yes)
			)
		)
		(property "Footprint" "antmicro-footprints:R_0402_1005Metric"
			(at 365.76 220.98 0)
			(effects
				(font
					(size 1.27 1.27)
					(thickness 0.15)
				)
				(justify left bottom)
				(hide yes)
			)
		)
		(property "Datasheet" "https://industrial.panasonic.com/cdbs/www-data/pdf/RDA0000/AOA0000C301.pdf"
			(at 365.76 223.52 0)
			(effects
				(font
					(size 1.27 1.27)
					(thickness 0.15)
				)
				(justify left bottom)
				(hide yes)
			)
		)
		(property "Description" ""
			(at 345.44 205.74 0)
			(effects
				(font
					(size 1.27 1.27)
				)
			)
		)
		(property "Manufacturer" "Panasonic"
			(at 365.76 228.6 0)
			(effects
				(font
					(size 1.27 1.27)
					(thickness 0.15)
				)
				(justify left bottom)
				(hide yes)
			)
		)
		(property "MPN" "ERJ2GE0R00X"
			(at 365.76 226.06 0)
			(effects
				(font
					(size 1.27 1.27)
					(thickness 0.15)
				)
				(justify left bottom)
				(hide yes)
			)
		)
		(property "Val" "0R"
			(at 344.17 204.47 0)
			(effects
				(font
					(size 1.27 1.27)
					(thickness 0.15)
				)
			)
		)
		(property "License" "Apache-2.0"
			(at 365.76 231.14 0)
			(effects
				(font
					(size 1.27 1.27)
					(thickness 0.15)
				)
				(justify left bottom)
				(hide yes)
			)
		)
		(property "Author" "Antmicro"
			(at 365.76 233.68 0)
			(effects
				(font
					(size 1.27 1.27)
					(thickness 0.15)
				)
				(justify left bottom)
				(hide yes)
			)
		)
		(property "Tolerance" "~"
			(at 365.76 215.9 0)
			(effects
				(font
					(size 1.27 1.27)
				)
				(justify left bottom)
				(hide yes)
			)
		)
		(property "Current" "1A"
			(at 347.98 214.63 0)
			(effects
				(font
					(size 1.27 1.27)
					(thickness 0.15)
				)
				(hide yes)
			)
		)
		(pin "1"
		)
		(pin "2"
		)
		(instances
			(project "k410t-devboard"
				(path ""
					(reference "R186")
					(unit 1)
				)
			)
		)
	)
	(symbol
		(lib_id "antmicroSlideSwitches:SW_CVS-08TB")
		(at 266.7 257.81 0)
		(unit 1)
		(exclude_from_sim no)
		(in_bom yes)
		(on_board yes)
		(dnp no)
		(fields_autoplaced yes)
		(property "Reference" "SW3"
			(at 273.0517 250.19 0)
			(effects
				(font
					(size 1.27 1.27)
				)
			)
		)
		(property "Value" "SW_CVS-08TB"
			(at 273.05 254 0)
			(effects
				(font
					(size 1.27 1.27)
					(thickness 0.15)
				)
				(hide yes)
			)
		)
		(property "Footprint" "antmicro-footprints:SW_DIP_SPSTx08_Slide_Copal_CVS-08xB_W5.9mm_P1mm"
			(at 293.37 265.43 0)
			(effects
				(font
					(size 1.27 1.27)
					(thickness 0.15)
				)
				(justify left bottom)
				(hide yes)
			)
		)
		(property "Datasheet" "https://www.mouser.com/datasheet/2/972/cvs-1827291.pdf"
			(at 293.37 267.97 0)
			(effects
				(font
					(size 1.27 1.27)
					(thickness 0.15)
				)
				(justify left bottom)
				(hide yes)
			)
		)
		(property "Description" ""
			(at 266.7 257.81 0)
			(effects
				(font
					(size 1.27 1.27)
				)
			)
		)
		(property "MPN" "CVS-08TB"
			(at 273.0517 252.73 0)
			(effects
				(font
					(size 1.27 1.27)
					(thickness 0.15)
				)
			)
		)
		(property "Manufacturer" "Nidec Components"
			(at 293.37 273.05 0)
			(effects
				(font
					(size 1.27 1.27)
					(thickness 0.15)
				)
				(justify left bottom)
				(hide yes)
			)
		)
		(property "Author" "Antmicro"
			(at 293.37 275.59 0)
			(effects
				(font
					(size 1.27 1.27)
					(thickness 0.15)
				)
				(justify left bottom)
				(hide yes)
			)
		)
		(property "License" "Apache-2.0"
			(at 293.37 278.13 0)
			(effects
				(font
					(size 1.27 1.27)
					(thickness 0.15)
				)
				(justify left bottom)
				(hide yes)
			)
		)
		(pin "1"
		)
		(pin "10"
		)
		(pin "11"
		)
		(pin "12"
		)
		(pin "13"
		)
		(pin "14"
		)
		(pin "15"
		)
		(pin "16"
		)
		(pin "17"
		)
		(pin "2"
		)
		(pin "3"
		)
		(pin "4"
		)
		(pin "5"
		)
		(pin "6"
		)
		(pin "7"
		)
		(pin "8"
		)
		(pin "9"
		)
		(instances
			(project "k410t-devboard"
				(path ""
					(reference "SW3")
					(unit 1)
				)
			)
		)
	)
	(symbol
		(lib_id "antmicropower:GND")
		(at 281.94 279.4 0)
		(unit 1)
		(exclude_from_sim no)
		(in_bom yes)
		(on_board yes)
		(dnp no)
		(property "Reference" "#PWR0253"
			(at 281.94 285.75 0)
			(effects
				(font
					(size 1.27 1.27)
				)
				(hide yes)
			)
		)
		(property "Value" "GND"
			(at 281.94 283.21 0)
			(effects
				(font
					(size 1.27 1.27)
				)
			)
		)
		(property "Footprint" ""
			(at 290.83 287.02 0)
			(effects
				(font
					(size 1.27 1.27)
					(thickness 0.15)
				)
				(justify left bottom)
				(hide yes)
			)
		)
		(property "Datasheet" ""
			(at 290.83 292.1 0)
			(effects
				(font
					(size 1.27 1.27)
					(thickness 0.15)
				)
				(justify left bottom)
				(hide yes)
			)
		)
		(property "Description" ""
			(at 281.94 279.4 0)
			(effects
				(font
					(size 1.27 1.27)
				)
			)
		)
		(property "Author" "Antmicro"
			(at 290.83 287.02 0)
			(effects
				(font
					(size 1.27 1.27)
					(thickness 0.15)
				)
				(justify left bottom)
				(hide yes)
			)
		)
		(property "License" "Apache-2.0"
			(at 290.83 289.56 0)
			(effects
				(font
					(size 1.27 1.27)
					(thickness 0.15)
				)
				(justify left bottom)
				(hide yes)
			)
		)
		(pin "1"
		)
		(instances
			(project "k410t-devboard"
				(path ""
					(reference "#PWR0253")
					(unit 1)
				)
			)
		)
	)
	(symbol
		(lib_id "antmicropower:+5V")
		(at 353.06 72.39 0)
		(unit 1)
		(exclude_from_sim no)
		(in_bom yes)
		(on_board yes)
		(dnp no)
		(property "Reference" "#PWR0464"
			(at 353.06 76.2 0)
			(effects
				(font
					(size 1.27 1.27)
				)
				(hide yes)
			)
		)
		(property "Value" "+5V"
			(at 353.06 68.58 0)
			(effects
				(font
					(size 1.27 1.27)
				)
			)
		)
		(property "Footprint" ""
			(at 353.06 72.39 0)
			(effects
				(font
					(size 1.27 1.27)
				)
				(hide yes)
			)
		)
		(property "Datasheet" ""
			(at 353.06 72.39 0)
			(effects
				(font
					(size 1.27 1.27)
				)
				(hide yes)
			)
		)
		(property "Description" ""
			(at 353.06 72.39 0)
			(effects
				(font
					(size 1.27 1.27)
				)
			)
		)
		(property "Author" "Antmicro"
			(at 368.3 80.01 0)
			(effects
				(font
					(size 1.27 1.27)
					(thickness 0.15)
				)
				(justify left bottom)
				(hide yes)
			)
		)
		(property "License" "Apache-2.0"
			(at 368.3 82.55 0)
			(effects
				(font
					(size 1.27 1.27)
					(thickness 0.15)
				)
				(justify left bottom)
				(hide yes)
			)
		)
		(pin "1"
		)
		(instances
			(project "k410t-devboard"
				(path ""
					(reference "#PWR0464")
					(unit 1)
				)
			)
		)
	)
	(symbol
		(lib_id "antmicropower:GND")
		(at 173.99 134.62 0)
		(mirror y)
		(unit 1)
		(exclude_from_sim no)
		(in_bom yes)
		(on_board yes)
		(dnp no)
		(property "Reference" "#PWR0243"
			(at 173.99 140.97 0)
			(effects
				(font
					(size 1.27 1.27)
				)
				(hide yes)
			)
		)
		(property "Value" "GND"
			(at 173.99 138.43 0)
			(effects
				(font
					(size 1.27 1.27)
				)
			)
		)
		(property "Footprint" ""
			(at 165.1 142.24 0)
			(effects
				(font
					(size 1.27 1.27)
					(thickness 0.15)
				)
				(justify left bottom)
				(hide yes)
			)
		)
		(property "Datasheet" ""
			(at 165.1 147.32 0)
			(effects
				(font
					(size 1.27 1.27)
					(thickness 0.15)
				)
				(justify left bottom)
				(hide yes)
			)
		)
		(property "Description" ""
			(at 173.99 134.62 0)
			(effects
				(font
					(size 1.27 1.27)
				)
			)
		)
		(property "Author" "Antmicro"
			(at 165.1 142.24 0)
			(effects
				(font
					(size 1.27 1.27)
					(thickness 0.15)
				)
				(justify left bottom)
				(hide yes)
			)
		)
		(property "License" "Apache-2.0"
			(at 165.1 144.78 0)
			(effects
				(font
					(size 1.27 1.27)
					(thickness 0.15)
				)
				(justify left bottom)
				(hide yes)
			)
		)
		(pin "1"
		)
		(instances
			(project "k410t-devboard"
				(path ""
					(reference "#PWR0243")
					(unit 1)
				)
			)
		)
	)
	(symbol
		(lib_id "antmicropower:GND")
		(at 163.83 237.49 0)
		(unit 1)
		(exclude_from_sim no)
		(in_bom yes)
		(on_board yes)
		(dnp no)
		(fields_autoplaced yes)
		(property "Reference" "#PWR0239"
			(at 163.83 243.84 0)
			(effects
				(font
					(size 1.27 1.27)
				)
				(hide yes)
			)
		)
		(property "Value" "GND"
			(at 163.83 241.935 0)
			(effects
				(font
					(size 1.27 1.27)
				)
			)
		)
		(property "Footprint" ""
			(at 172.72 245.11 0)
			(effects
				(font
					(size 1.27 1.27)
					(thickness 0.15)
				)
				(justify left bottom)
				(hide yes)
			)
		)
		(property "Datasheet" ""
			(at 172.72 250.19 0)
			(effects
				(font
					(size 1.27 1.27)
					(thickness 0.15)
				)
				(justify left bottom)
				(hide yes)
			)
		)
		(property "Description" ""
			(at 163.83 237.49 0)
			(effects
				(font
					(size 1.27 1.27)
				)
			)
		)
		(property "Author" "Antmicro"
			(at 172.72 245.11 0)
			(effects
				(font
					(size 1.27 1.27)
					(thickness 0.15)
				)
				(justify left bottom)
				(hide yes)
			)
		)
		(property "License" "Apache-2.0"
			(at 172.72 247.65 0)
			(effects
				(font
					(size 1.27 1.27)
					(thickness 0.15)
				)
				(justify left bottom)
				(hide yes)
			)
		)
		(pin "1"
		)
		(instances
			(project "k410t-devboard"
				(path ""
					(reference "#PWR0239")
					(unit 1)
				)
			)
		)
	)
	(symbol
		(lib_id "antmicropower:GND")
		(at 137.16 153.67 0)
		(unit 1)
		(exclude_from_sim no)
		(in_bom yes)
		(on_board yes)
		(dnp no)
		(property "Reference" "#PWR0225"
			(at 137.16 160.02 0)
			(effects
				(font
					(size 1.27 1.27)
				)
				(hide yes)
			)
		)
		(property "Value" "GND"
			(at 137.16 157.48 0)
			(effects
				(font
					(size 1.27 1.27)
				)
			)
		)
		(property "Footprint" ""
			(at 146.05 161.29 0)
			(effects
				(font
					(size 1.27 1.27)
					(thickness 0.15)
				)
				(justify left bottom)
				(hide yes)
			)
		)
		(property "Datasheet" ""
			(at 146.05 166.37 0)
			(effects
				(font
					(size 1.27 1.27)
					(thickness 0.15)
				)
				(justify left bottom)
				(hide yes)
			)
		)
		(property "Description" ""
			(at 137.16 153.67 0)
			(effects
				(font
					(size 1.27 1.27)
				)
			)
		)
		(property "Author" "Antmicro"
			(at 146.05 161.29 0)
			(effects
				(font
					(size 1.27 1.27)
					(thickness 0.15)
				)
				(justify left bottom)
				(hide yes)
			)
		)
		(property "License" "Apache-2.0"
			(at 146.05 163.83 0)
			(effects
				(font
					(size 1.27 1.27)
					(thickness 0.15)
				)
				(justify left bottom)
				(hide yes)
			)
		)
		(pin "1"
		)
		(instances
			(project "k410t-devboard"
				(path ""
					(reference "#PWR0225")
					(unit 1)
				)
			)
		)
	)
	(symbol
		(lib_id "antmicropower:GND")
		(at 365.76 246.38 0)
		(unit 1)
		(exclude_from_sim no)
		(in_bom yes)
		(on_board yes)
		(dnp no)
		(property "Reference" "#PWR0274"
			(at 365.76 252.73 0)
			(effects
				(font
					(size 1.27 1.27)
				)
				(hide yes)
			)
		)
		(property "Value" "GND"
			(at 365.76 250.19 0)
			(effects
				(font
					(size 1.27 1.27)
				)
			)
		)
		(property "Footprint" ""
			(at 374.65 254 0)
			(effects
				(font
					(size 1.27 1.27)
					(thickness 0.15)
				)
				(justify left bottom)
				(hide yes)
			)
		)
		(property "Datasheet" ""
			(at 374.65 259.08 0)
			(effects
				(font
					(size 1.27 1.27)
					(thickness 0.15)
				)
				(justify left bottom)
				(hide yes)
			)
		)
		(property "Description" ""
			(at 365.76 246.38 0)
			(effects
				(font
					(size 1.27 1.27)
				)
			)
		)
		(property "Author" "Antmicro"
			(at 374.65 254 0)
			(effects
				(font
					(size 1.27 1.27)
					(thickness 0.15)
				)
				(justify left bottom)
				(hide yes)
			)
		)
		(property "License" "Apache-2.0"
			(at 374.65 256.54 0)
			(effects
				(font
					(size 1.27 1.27)
					(thickness 0.15)
				)
				(justify left bottom)
				(hide yes)
			)
		)
		(pin "1"
		)
		(instances
			(project "k410t-devboard"
				(path ""
					(reference "#PWR0274")
					(unit 1)
				)
			)
		)
	)
	(symbol
		(lib_id "antmicroResistors0402:R_5k1_0402")
		(at 271.78 48.26 0)
		(unit 1)
		(exclude_from_sim no)
		(in_bom yes)
		(on_board yes)
		(dnp no)
		(property "Reference" "R361"
			(at 279.4 46.99 0)
			(effects
				(font
					(size 1.27 1.27)
				)
			)
		)
		(property "Value" "R_5k1_0402"
			(at 292.1 60.96 0)
			(effects
				(font
					(size 1.27 1.27)
					(thickness 0.15)
				)
				(justify left bottom)
				(hide yes)
			)
		)
		(property "Footprint" "antmicro-footprints:R_0402_1005Metric"
			(at 292.1 63.5 0)
			(effects
				(font
					(size 1.27 1.27)
					(thickness 0.15)
				)
				(justify left bottom)
				(hide yes)
			)
		)
		(property "Datasheet" "https://www.bourns.com/docs/product-datasheets/cr.pdf"
			(at 292.1 66.04 0)
			(effects
				(font
					(size 1.27 1.27)
					(thickness 0.15)
				)
				(justify left bottom)
				(hide yes)
			)
		)
		(property "Description" ""
			(at 271.78 48.26 0)
			(effects
				(font
					(size 1.27 1.27)
				)
			)
		)
		(property "Manufacturer" "Bourns"
			(at 292.1 71.12 0)
			(effects
				(font
					(size 1.27 1.27)
					(thickness 0.15)
				)
				(justify left bottom)
				(hide yes)
			)
		)
		(property "MPN" "CR0402-FX-5101GLF"
			(at 292.1 68.58 0)
			(effects
				(font
					(size 1.27 1.27)
					(thickness 0.15)
				)
				(justify left bottom)
				(hide yes)
			)
		)
		(property "Val" "5k1"
			(at 269.875 46.99 0)
			(effects
				(font
					(size 1.27 1.27)
					(thickness 0.15)
				)
			)
		)
		(property "License" "Apache-2.0"
			(at 292.1 73.66 0)
			(effects
				(font
					(size 1.27 1.27)
					(thickness 0.15)
				)
				(justify left bottom)
				(hide yes)
			)
		)
		(property "Author" "Antmicro"
			(at 292.1 76.2 0)
			(effects
				(font
					(size 1.27 1.27)
					(thickness 0.15)
				)
				(justify left bottom)
				(hide yes)
			)
		)
		(property "Tolerance" "1%"
			(at 292.1 58.42 0)
			(effects
				(font
					(size 1.27 1.27)
				)
				(justify left bottom)
				(hide yes)
			)
		)
		(pin "1"
		)
		(pin "2"
		)
		(instances
			(project "k410t-devboard"
				(path ""
					(reference "R361")
					(unit 1)
				)
			)
		)
	)
	(symbol
		(lib_id "antmicroDiodesRectifiersSingle:BAT54-02V-G3-08")
		(at 377.19 195.58 270)
		(mirror x)
		(unit 1)
		(exclude_from_sim no)
		(in_bom yes)
		(on_board yes)
		(dnp no)
		(property "Reference" "D38"
			(at 374.65 191.77 90)
			(effects
				(font
					(size 1.27 1.27)
				)
				(justify right)
			)
		)
		(property "Value" "BAT54-02V-G3-08"
			(at 382.905 204.47 0)
			(effects
				(font
					(size 1.27 1.27)
					(thickness 0.15)
				)
				(justify left)
				(hide yes)
			)
		)
		(property "Footprint" "antmicro-footprints:SOD-523"
			(at 367.03 173.99 0)
			(effects
				(font
					(size 1.27 1.27)
					(thickness 0.15)
				)
				(justify left bottom)
				(hide yes)
			)
		)
		(property "Datasheet" "https://www.vishay.com/docs/85633/bat5402v.pdf"
			(at 364.49 173.99 0)
			(effects
				(font
					(size 1.27 1.27)
					(thickness 0.15)
				)
				(justify left bottom)
				(hide yes)
			)
		)
		(property "Description" ""
			(at 377.19 195.58 0)
			(effects
				(font
					(size 1.27 1.27)
				)
			)
		)
		(property "MPN" "BAT54-02V-G3-08"
			(at 374.65 194.31 90)
			(effects
				(font
					(size 1.27 1.27)
					(thickness 0.15)
				)
				(justify right)
			)
		)
		(property "Manufacturer" "Vishay"
			(at 359.41 173.99 0)
			(effects
				(font
					(size 1.27 1.27)
					(thickness 0.15)
				)
				(justify left bottom)
				(hide yes)
			)
		)
		(property "Author" "Antmicro"
			(at 356.87 173.99 0)
			(effects
				(font
					(size 1.27 1.27)
					(thickness 0.15)
				)
				(justify left bottom)
				(hide yes)
			)
		)
		(property "License" "Apache-2.0"
			(at 354.33 173.99 0)
			(effects
				(font
					(size 1.27 1.27)
					(thickness 0.15)
				)
				(justify left bottom)
				(hide yes)
			)
		)
		(property "Public" "False"
			(at 359.41 175.26 0)
			(effects
				(font
					(size 1.27 1.27)
				)
				(justify left bottom)
				(hide yes)
			)
		)
		(pin "1"
		)
		(pin "2"
		)
		(instances
			(project "k410t-devboard"
				(path ""
					(reference "D38")
					(unit 1)
				)
			)
		)
	)
	(symbol
		(lib_id "antmicropower:GND")
		(at 375.92 246.38 0)
		(unit 1)
		(exclude_from_sim no)
		(in_bom yes)
		(on_board yes)
		(dnp no)
		(property "Reference" "#PWR0275"
			(at 375.92 252.73 0)
			(effects
				(font
					(size 1.27 1.27)
				)
				(hide yes)
			)
		)
		(property "Value" "GND"
			(at 375.92 250.19 0)
			(effects
				(font
					(size 1.27 1.27)
				)
			)
		)
		(property "Footprint" ""
			(at 384.81 254 0)
			(effects
				(font
					(size 1.27 1.27)
					(thickness 0.15)
				)
				(justify left bottom)
				(hide yes)
			)
		)
		(property "Datasheet" ""
			(at 384.81 259.08 0)
			(effects
				(font
					(size 1.27 1.27)
					(thickness 0.15)
				)
				(justify left bottom)
				(hide yes)
			)
		)
		(property "Description" ""
			(at 375.92 246.38 0)
			(effects
				(font
					(size 1.27 1.27)
				)
			)
		)
		(property "Author" "Antmicro"
			(at 384.81 254 0)
			(effects
				(font
					(size 1.27 1.27)
					(thickness 0.15)
				)
				(justify left bottom)
				(hide yes)
			)
		)
		(property "License" "Apache-2.0"
			(at 384.81 256.54 0)
			(effects
				(font
					(size 1.27 1.27)
					(thickness 0.15)
				)
				(justify left bottom)
				(hide yes)
			)
		)
		(pin "1"
		)
		(instances
			(project "k410t-devboard"
				(path ""
					(reference "#PWR0275")
					(unit 1)
				)
			)
		)
	)
	(symbol
		(lib_id "antmicroResistors0402:R_0R_0402")
		(at 359.41 210.82 0)
		(unit 1)
		(exclude_from_sim no)
		(in_bom yes)
		(on_board yes)
		(dnp no)
		(property "Reference" "R188"
			(at 367.03 209.55 0)
			(effects
				(font
					(size 1.27 1.27)
				)
			)
		)
		(property "Value" "R_0R_0402"
			(at 379.73 223.52 0)
			(effects
				(font
					(size 1.27 1.27)
					(thickness 0.15)
				)
				(justify left bottom)
				(hide yes)
			)
		)
		(property "Footprint" "antmicro-footprints:R_0402_1005Metric"
			(at 379.73 226.06 0)
			(effects
				(font
					(size 1.27 1.27)
					(thickness 0.15)
				)
				(justify left bottom)
				(hide yes)
			)
		)
		(property "Datasheet" "https://industrial.panasonic.com/cdbs/www-data/pdf/RDA0000/AOA0000C301.pdf"
			(at 379.73 228.6 0)
			(effects
				(font
					(size 1.27 1.27)
					(thickness 0.15)
				)
				(justify left bottom)
				(hide yes)
			)
		)
		(property "Description" ""
			(at 359.41 210.82 0)
			(effects
				(font
					(size 1.27 1.27)
				)
			)
		)
		(property "Manufacturer" "Panasonic"
			(at 379.73 233.68 0)
			(effects
				(font
					(size 1.27 1.27)
					(thickness 0.15)
				)
				(justify left bottom)
				(hide yes)
			)
		)
		(property "MPN" "ERJ2GE0R00X"
			(at 379.73 231.14 0)
			(effects
				(font
					(size 1.27 1.27)
					(thickness 0.15)
				)
				(justify left bottom)
				(hide yes)
			)
		)
		(property "Val" "0R"
			(at 358.14 209.55 0)
			(effects
				(font
					(size 1.27 1.27)
					(thickness 0.15)
				)
			)
		)
		(property "License" "Apache-2.0"
			(at 379.73 236.22 0)
			(effects
				(font
					(size 1.27 1.27)
					(thickness 0.15)
				)
				(justify left bottom)
				(hide yes)
			)
		)
		(property "Author" "Antmicro"
			(at 379.73 238.76 0)
			(effects
				(font
					(size 1.27 1.27)
					(thickness 0.15)
				)
				(justify left bottom)
				(hide yes)
			)
		)
		(property "Tolerance" "~"
			(at 379.73 220.98 0)
			(effects
				(font
					(size 1.27 1.27)
				)
				(justify left bottom)
				(hide yes)
			)
		)
		(property "Current" "1A"
			(at 361.95 219.71 0)
			(effects
				(font
					(size 1.27 1.27)
					(thickness 0.15)
				)
				(hide yes)
			)
		)
		(pin "1"
		)
		(pin "2"
		)
		(instances
			(project "k410t-devboard"
				(path ""
					(reference "R188")
					(unit 1)
				)
			)
		)
	)
	(symbol
		(lib_id "antmicroResistors0402:R_15k_0402")
		(at 285.75 69.85 270)
		(mirror x)
		(unit 1)
		(exclude_from_sim no)
		(in_bom no)
		(on_board yes)
		(dnp yes)
		(property "Reference" "R169"
			(at 284.48 66.04 90)
			(effects
				(font
					(size 1.27 1.27)
				)
				(justify right)
			)
		)
		(property "Value" "R_15k_0402"
			(at 273.05 49.53 0)
			(effects
				(font
					(size 1.27 1.27)
					(thickness 0.15)
				)
				(justify left bottom)
				(hide yes)
			)
		)
		(property "Footprint" "antmicro-footprints:R_0402_1005Metric"
			(at 270.51 49.53 0)
			(effects
				(font
					(size 1.27 1.27)
					(thickness 0.15)
				)
				(justify left bottom)
				(hide yes)
			)
		)
		(property "Datasheet" "https://www.bourns.com/docs/product-datasheets/cr.pdf"
			(at 267.97 49.53 0)
			(effects
				(font
					(size 1.27 1.27)
					(thickness 0.15)
				)
				(justify left bottom)
				(hide yes)
			)
		)
		(property "Description" ""
			(at 285.75 69.85 0)
			(effects
				(font
					(size 1.27 1.27)
				)
			)
		)
		(property "Manufacturer" "Bourns"
			(at 262.89 49.53 0)
			(effects
				(font
					(size 1.27 1.27)
					(thickness 0.15)
				)
				(justify left bottom)
				(hide yes)
			)
		)
		(property "MPN" "CR0402-FX-1502GLF"
			(at 265.43 49.53 0)
			(effects
				(font
					(size 1.27 1.27)
					(thickness 0.15)
				)
				(justify left bottom)
				(hide yes)
			)
		)
		(property "Val" "15k"
			(at 284.48 68.58 90)
			(effects
				(font
					(size 1.27 1.27)
					(thickness 0.15)
				)
				(justify right)
			)
		)
		(property "DNP" "DNP"
			(at 285.75 65.405 0)
			(effects
				(font
					(size 1.27 1.27)
				)
				(justify right)
			)
		)
		(property "License" "Apache-2.0"
			(at 260.35 49.53 0)
			(effects
				(font
					(size 1.27 1.27)
					(thickness 0.15)
				)
				(justify left bottom)
				(hide yes)
			)
		)
		(property "Author" "Antmicro"
			(at 257.81 49.53 0)
			(effects
				(font
					(size 1.27 1.27)
					(thickness 0.15)
				)
				(justify left bottom)
				(hide yes)
			)
		)
		(property "Tolerance" "1%"
			(at 275.59 49.53 0)
			(effects
				(font
					(size 1.27 1.27)
				)
				(justify left bottom)
				(hide yes)
			)
		)
		(pin "1"
		)
		(pin "2"
		)
		(instances
			(project "k410t-devboard"
				(path ""
					(reference "R169")
					(unit 1)
				)
			)
		)
	)
	(symbol
		(lib_id "antmicropower:GND")
		(at 63.5 173.99 0)
		(unit 1)
		(exclude_from_sim no)
		(in_bom yes)
		(on_board yes)
		(dnp no)
		(property "Reference" "#PWR0205"
			(at 63.5 180.34 0)
			(effects
				(font
					(size 1.27 1.27)
				)
				(hide yes)
			)
		)
		(property "Value" "GND"
			(at 63.5 177.8 0)
			(effects
				(font
					(size 1.27 1.27)
				)
			)
		)
		(property "Footprint" ""
			(at 72.39 181.61 0)
			(effects
				(font
					(size 1.27 1.27)
					(thickness 0.15)
				)
				(justify left bottom)
				(hide yes)
			)
		)
		(property "Datasheet" ""
			(at 72.39 186.69 0)
			(effects
				(font
					(size 1.27 1.27)
					(thickness 0.15)
				)
				(justify left bottom)
				(hide yes)
			)
		)
		(property "Description" ""
			(at 63.5 173.99 0)
			(effects
				(font
					(size 1.27 1.27)
				)
			)
		)
		(property "Author" "Antmicro"
			(at 72.39 181.61 0)
			(effects
				(font
					(size 1.27 1.27)
					(thickness 0.15)
				)
				(justify left bottom)
				(hide yes)
			)
		)
		(property "License" "Apache-2.0"
			(at 72.39 184.15 0)
			(effects
				(font
					(size 1.27 1.27)
					(thickness 0.15)
				)
				(justify left bottom)
				(hide yes)
			)
		)
		(pin "1"
		)
		(instances
			(project "k410t-devboard"
				(path ""
					(reference "#PWR0205")
					(unit 1)
				)
			)
		)
	)
	(symbol
		(lib_id "antmicropower:GND")
		(at 147.32 90.17 0)
		(unit 1)
		(exclude_from_sim no)
		(in_bom yes)
		(on_board yes)
		(dnp no)
		(fields_autoplaced yes)
		(property "Reference" "#PWR0228"
			(at 147.32 96.52 0)
			(effects
				(font
					(size 1.27 1.27)
				)
				(hide yes)
			)
		)
		(property "Value" "GND"
			(at 147.32 95.25 0)
			(effects
				(font
					(size 1.27 1.27)
				)
			)
		)
		(property "Footprint" ""
			(at 156.21 97.79 0)
			(effects
				(font
					(size 1.27 1.27)
					(thickness 0.15)
				)
				(justify left bottom)
				(hide yes)
			)
		)
		(property "Datasheet" ""
			(at 156.21 102.87 0)
			(effects
				(font
					(size 1.27 1.27)
					(thickness 0.15)
				)
				(justify left bottom)
				(hide yes)
			)
		)
		(property "Description" ""
			(at 147.32 90.17 0)
			(effects
				(font
					(size 1.27 1.27)
				)
			)
		)
		(property "Author" "Antmicro"
			(at 156.21 97.79 0)
			(effects
				(font
					(size 1.27 1.27)
					(thickness 0.15)
				)
				(justify left bottom)
				(hide yes)
			)
		)
		(property "License" "Apache-2.0"
			(at 156.21 100.33 0)
			(effects
				(font
					(size 1.27 1.27)
					(thickness 0.15)
				)
				(justify left bottom)
				(hide yes)
			)
		)
		(pin "1"
		)
		(instances
			(project "k410t-devboard"
				(path ""
					(reference "#PWR0228")
					(unit 1)
				)
			)
		)
	)
	(symbol
		(lib_id "antmicroResonators:Resonator_12MHz_ABM8G")
		(at 113.03 85.09 0)
		(unit 1)
		(exclude_from_sim no)
		(in_bom yes)
		(on_board yes)
		(dnp no)
		(property "Reference" "Y1"
			(at 116.84 78.74 0)
			(effects
				(font
					(size 1.27 1.27)
				)
			)
		)
		(property "Value" "Resonator_12MHz_ABM8G"
			(at 128.27 97.79 0)
			(effects
				(font
					(size 1.27 1.27)
					(thickness 0.15)
				)
				(justify left bottom)
				(hide yes)
			)
		)
		(property "Footprint" "antmicro-footprints:Resonator_SMD_Abracon_ABM8G_3.2x2.5mm"
			(at 128.27 100.33 0)
			(effects
				(font
					(size 1.27 1.27)
					(thickness 0.15)
				)
				(justify left bottom)
				(hide yes)
			)
		)
		(property "Datasheet" "https://abracon.com/Resonators/ABM8G.pdf"
			(at 128.27 102.87 0)
			(effects
				(font
					(size 1.27 1.27)
					(thickness 0.15)
				)
				(justify left bottom)
				(hide yes)
			)
		)
		(property "Description" ""
			(at 113.03 85.09 0)
			(effects
				(font
					(size 1.27 1.27)
				)
			)
		)
		(property "MPN" "ABM8G-12.000MHZ-18-D2Y-T"
			(at 128.27 92.71 0)
			(effects
				(font
					(size 1.27 1.27)
					(thickness 0.15)
				)
				(justify left bottom)
				(hide yes)
			)
		)
		(property "Manufacturer" "Abracon"
			(at 128.27 105.41 0)
			(effects
				(font
					(size 1.27 1.27)
					(thickness 0.15)
				)
				(justify left bottom)
				(hide yes)
			)
		)
		(property "Val" "12 MHz"
			(at 116.84 81.28 0)
			(effects
				(font
					(size 1.27 1.27)
					(thickness 0.15)
				)
			)
		)
		(property "Author" "Antmicro"
			(at 128.27 107.95 0)
			(effects
				(font
					(size 1.27 1.27)
					(thickness 0.15)
				)
				(justify left bottom)
				(hide yes)
			)
		)
		(property "License" "Apache-2.0"
			(at 128.27 110.49 0)
			(effects
				(font
					(size 1.27 1.27)
					(thickness 0.15)
				)
				(justify left bottom)
				(hide yes)
			)
		)
		(pin "1"
		)
		(pin "2"
		)
		(pin "3"
		)
		(pin "4"
		)
		(instances
			(project "k410t-devboard"
				(path ""
					(reference "Y1")
					(unit 1)
				)
			)
		)
	)
	(symbol
		(lib_id "antmicroResistors0402:R_10k_0402")
		(at 160.02 180.34 180)
		(unit 1)
		(exclude_from_sim no)
		(in_bom yes)
		(on_board yes)
		(dnp no)
		(property "Reference" "R159"
			(at 157.48 175.26 0)
			(effects
				(font
					(size 1.27 1.27)
				)
			)
		)
		(property "Value" "R_10k_0402"
			(at 139.7 167.64 0)
			(effects
				(font
					(size 1.27 1.27)
					(thickness 0.15)
				)
				(justify left bottom)
				(hide yes)
			)
		)
		(property "Footprint" "antmicro-footprints:R_0402_1005Metric"
			(at 139.7 165.1 0)
			(effects
				(font
					(size 1.27 1.27)
					(thickness 0.15)
				)
				(justify left bottom)
				(hide yes)
			)
		)
		(property "Datasheet" "https://www.bourns.com/docs/product-datasheets/cr.pdf"
			(at 139.7 162.56 0)
			(effects
				(font
					(size 1.27 1.27)
					(thickness 0.15)
				)
				(justify left bottom)
				(hide yes)
			)
		)
		(property "Description" ""
			(at 160.02 180.34 0)
			(effects
				(font
					(size 1.27 1.27)
				)
			)
		)
		(property "Manufacturer" "Bourns"
			(at 139.7 157.48 0)
			(effects
				(font
					(size 1.27 1.27)
					(thickness 0.15)
				)
				(justify left bottom)
				(hide yes)
			)
		)
		(property "MPN" "CR0402-FX-1002GLF"
			(at 139.7 160.02 0)
			(effects
				(font
					(size 1.27 1.27)
					(thickness 0.15)
				)
				(justify left bottom)
				(hide yes)
			)
		)
		(property "Val" "10k"
			(at 157.48 177.8 0)
			(effects
				(font
					(size 1.27 1.27)
					(thickness 0.15)
				)
			)
		)
		(property "License" "Apache-2.0"
			(at 139.7 154.94 0)
			(effects
				(font
					(size 1.27 1.27)
					(thickness 0.15)
				)
				(justify left bottom)
				(hide yes)
			)
		)
		(property "Author" "Antmicro"
			(at 139.7 152.4 0)
			(effects
				(font
					(size 1.27 1.27)
					(thickness 0.15)
				)
				(justify left bottom)
				(hide yes)
			)
		)
		(property "Tolerance" "1%"
			(at 139.7 170.18 0)
			(effects
				(font
					(size 1.27 1.27)
				)
				(justify left bottom)
				(hide yes)
			)
		)
		(pin "1"
		)
		(pin "2"
		)
		(instances
			(project "k410t-devboard"
				(path ""
					(reference "R159")
					(unit 1)
				)
			)
		)
	)
	(symbol
		(lib_id "antmicroResistors0402:R_10k_0402")
		(at 309.88 100.33 270)
		(mirror x)
		(unit 1)
		(exclude_from_sim no)
		(in_bom yes)
		(on_board yes)
		(dnp no)
		(property "Reference" "R192"
			(at 308.61 96.52 90)
			(effects
				(font
					(size 1.27 1.27)
				)
				(justify right)
			)
		)
		(property "Value" "R_10k_0402"
			(at 297.18 80.01 0)
			(effects
				(font
					(size 1.27 1.27)
					(thickness 0.15)
				)
				(justify left bottom)
				(hide yes)
			)
		)
		(property "Footprint" "antmicro-footprints:R_0402_1005Metric"
			(at 294.64 80.01 0)
			(effects
				(font
					(size 1.27 1.27)
					(thickness 0.15)
				)
				(justify left bottom)
				(hide yes)
			)
		)
		(property "Datasheet" "https://www.bourns.com/docs/product-datasheets/cr.pdf"
			(at 292.1 80.01 0)
			(effects
				(font
					(size 1.27 1.27)
					(thickness 0.15)
				)
				(justify left bottom)
				(hide yes)
			)
		)
		(property "Description" ""
			(at 309.88 100.33 0)
			(effects
				(font
					(size 1.27 1.27)
				)
			)
		)
		(property "Manufacturer" "Bourns"
			(at 287.02 80.01 0)
			(effects
				(font
					(size 1.27 1.27)
					(thickness 0.15)
				)
				(justify left bottom)
				(hide yes)
			)
		)
		(property "MPN" "CR0402-FX-1002GLF"
			(at 289.56 80.01 0)
			(effects
				(font
					(size 1.27 1.27)
					(thickness 0.15)
				)
				(justify left bottom)
				(hide yes)
			)
		)
		(property "Val" "10k"
			(at 308.61 99.06 90)
			(effects
				(font
					(size 1.27 1.27)
					(thickness 0.15)
				)
				(justify right)
			)
		)
		(property "License" "Apache-2.0"
			(at 284.48 80.01 0)
			(effects
				(font
					(size 1.27 1.27)
					(thickness 0.15)
				)
				(justify left bottom)
				(hide yes)
			)
		)
		(property "Author" "Antmicro"
			(at 281.94 80.01 0)
			(effects
				(font
					(size 1.27 1.27)
					(thickness 0.15)
				)
				(justify left bottom)
				(hide yes)
			)
		)
		(property "Tolerance" "1%"
			(at 299.72 80.01 0)
			(effects
				(font
					(size 1.27 1.27)
				)
				(justify left bottom)
				(hide yes)
			)
		)
		(pin "1"
		)
		(pin "2"
		)
		(instances
			(project "k410t-devboard"
				(path ""
					(reference "R192")
					(unit 1)
				)
			)
		)
	)
	(symbol
		(lib_id "antmicropower:+5V")
		(at 341.63 74.93 0)
		(unit 1)
		(exclude_from_sim no)
		(in_bom yes)
		(on_board yes)
		(dnp no)
		(property "Reference" "#PWR0463"
			(at 341.63 78.74 0)
			(effects
				(font
					(size 1.27 1.27)
				)
				(hide yes)
			)
		)
		(property "Value" "+5V"
			(at 341.63 71.12 0)
			(effects
				(font
					(size 1.27 1.27)
				)
			)
		)
		(property "Footprint" ""
			(at 341.63 74.93 0)
			(effects
				(font
					(size 1.27 1.27)
				)
				(hide yes)
			)
		)
		(property "Datasheet" ""
			(at 341.63 74.93 0)
			(effects
				(font
					(size 1.27 1.27)
				)
				(hide yes)
			)
		)
		(property "Description" ""
			(at 341.63 74.93 0)
			(effects
				(font
					(size 1.27 1.27)
				)
			)
		)
		(property "Author" "Antmicro"
			(at 356.87 82.55 0)
			(effects
				(font
					(size 1.27 1.27)
					(thickness 0.15)
				)
				(justify left bottom)
				(hide yes)
			)
		)
		(property "License" "Apache-2.0"
			(at 356.87 85.09 0)
			(effects
				(font
					(size 1.27 1.27)
					(thickness 0.15)
				)
				(justify left bottom)
				(hide yes)
			)
		)
		(pin "1"
		)
		(instances
			(project "k410t-devboard"
				(path ""
					(reference "#PWR0463")
					(unit 1)
				)
			)
		)
	)
	(symbol
		(lib_id "antmicroResistors0402:R_330R_0402")
		(at 80.01 245.11 0)
		(unit 1)
		(exclude_from_sim no)
		(in_bom yes)
		(on_board yes)
		(dnp no)
		(property "Reference" "R150"
			(at 85.09 245.11 0)
			(effects
				(font
					(size 1.524 1.524)
				)
				(justify left bottom)
			)
		)
		(property "Value" "R_330R_0402"
			(at 100.33 257.81 0)
			(effects
				(font
					(size 1.27 1.27)
					(thickness 0.15)
				)
				(justify left bottom)
				(hide yes)
			)
		)
		(property "Footprint" "antmicro-footprints:R_0402_1005Metric"
			(at 100.33 260.35 0)
			(effects
				(font
					(size 1.27 1.27)
					(thickness 0.15)
				)
				(justify left bottom)
				(hide yes)
			)
		)
		(property "Datasheet" "https://www.bourns.com/docs/product-datasheets/cr.pdf"
			(at 100.33 262.89 0)
			(effects
				(font
					(size 1.27 1.27)
					(thickness 0.15)
				)
				(justify left bottom)
				(hide yes)
			)
		)
		(property "Description" ""
			(at 80.01 245.11 0)
			(effects
				(font
					(size 1.27 1.27)
				)
			)
		)
		(property "Manufacturer" "Bourns"
			(at 100.33 267.97 0)
			(effects
				(font
					(size 1.27 1.27)
					(thickness 0.15)
				)
				(justify left bottom)
				(hide yes)
			)
		)
		(property "MPN" "CR0402-FX-3300GLF"
			(at 100.33 265.43 0)
			(effects
				(font
					(size 1.27 1.27)
					(thickness 0.15)
				)
				(justify left bottom)
				(hide yes)
			)
		)
		(property "Val" "330R"
			(at 74.93 245.11 0)
			(effects
				(font
					(size 1.27 1.27)
					(thickness 0.15)
				)
				(justify left bottom)
			)
		)
		(property "License" "Apache-2.0"
			(at 100.33 270.51 0)
			(effects
				(font
					(size 1.27 1.27)
					(thickness 0.15)
				)
				(justify left bottom)
				(hide yes)
			)
		)
		(property "Author" "Antmicro"
			(at 100.33 273.05 0)
			(effects
				(font
					(size 1.27 1.27)
					(thickness 0.15)
				)
				(justify left bottom)
				(hide yes)
			)
		)
		(property "Tolerance" "1%"
			(at 100.33 255.27 0)
			(effects
				(font
					(size 1.27 1.27)
				)
				(justify left bottom)
				(hide yes)
			)
		)
		(pin "1"
		)
		(pin "2"
		)
		(instances
			(project "k410t-devboard"
				(path ""
					(reference "R150")
					(unit 1)
				)
			)
		)
	)
	(symbol
		(lib_id "antmicroCapacitors0402:C_10u_0402")
		(at 400.05 96.52 90)
		(unit 1)
		(exclude_from_sim no)
		(in_bom yes)
		(on_board yes)
		(dnp no)
		(property "Reference" "C397"
			(at 400.685 92.075 90)
			(effects
				(font
					(size 1.27 1.27)
				)
				(justify right)
			)
		)
		(property "Value" "C_10u_0402"
			(at 410.21 76.2 0)
			(effects
				(font
					(size 1.27 1.27)
					(thickness 0.15)
				)
				(justify left bottom)
				(hide yes)
			)
		)
		(property "Footprint" "antmicro-footprints:C_0402_1005Metric"
			(at 412.75 76.2 0)
			(effects
				(font
					(size 1.27 1.27)
					(thickness 0.15)
				)
				(justify left bottom)
				(hide yes)
			)
		)
		(property "Datasheet" "https://www.yageo.com/en/Chart/Download/pdf/CC0402MRX5R5BB106"
			(at 415.29 76.2 0)
			(effects
				(font
					(size 1.27 1.27)
					(thickness 0.15)
				)
				(justify left bottom)
				(hide yes)
			)
		)
		(property "Description" ""
			(at 400.05 96.52 0)
			(effects
				(font
					(size 1.27 1.27)
				)
			)
		)
		(property "Manufacturer" "YAGEO"
			(at 420.37 76.2 0)
			(effects
				(font
					(size 1.27 1.27)
					(thickness 0.15)
				)
				(justify left bottom)
				(hide yes)
			)
		)
		(property "MPN" "CC0402MRX5R5BB106"
			(at 417.83 76.2 0)
			(effects
				(font
					(size 1.27 1.27)
					(thickness 0.15)
				)
				(justify left bottom)
				(hide yes)
			)
		)
		(property "Val" "10u"
			(at 400.685 95.885 90)
			(effects
				(font
					(size 1.27 1.27)
					(thickness 0.15)
				)
				(justify right)
			)
		)
		(property "License" "Apache-2.0"
			(at 422.91 76.2 0)
			(effects
				(font
					(size 1.27 1.27)
					(thickness 0.15)
				)
				(justify left bottom)
				(hide yes)
			)
		)
		(property "Author" "Antmicro"
			(at 425.45 76.2 0)
			(effects
				(font
					(size 1.27 1.27)
					(thickness 0.15)
				)
				(justify left bottom)
				(hide yes)
			)
		)
		(property "Voltage" ""
			(at 427.99 76.2 0)
			(effects
				(font
					(size 1.27 1.27)
				)
				(justify left bottom)
				(hide yes)
			)
		)
		(property "Dielectric" ""
			(at 430.53 76.2 0)
			(effects
				(font
					(size 1.27 1.27)
				)
				(justify left bottom)
				(hide yes)
			)
		)
		(pin "1"
		)
		(pin "2"
		)
		(instances
			(project "k410t-devboard"
				(path ""
					(reference "C397")
					(unit 1)
				)
			)
		)
	)
	(symbol
		(lib_id "antmicropower:GND")
		(at 106.68 96.52 0)
		(unit 1)
		(exclude_from_sim no)
		(in_bom yes)
		(on_board yes)
		(dnp no)
		(property "Reference" "#PWR0214"
			(at 106.68 102.87 0)
			(effects
				(font
					(size 1.27 1.27)
				)
				(hide yes)
			)
		)
		(property "Value" "GND"
			(at 106.68 100.33 0)
			(effects
				(font
					(size 1.27 1.27)
				)
			)
		)
		(property "Footprint" ""
			(at 115.57 104.14 0)
			(effects
				(font
					(size 1.27 1.27)
					(thickness 0.15)
				)
				(justify left bottom)
				(hide yes)
			)
		)
		(property "Datasheet" ""
			(at 115.57 109.22 0)
			(effects
				(font
					(size 1.27 1.27)
					(thickness 0.15)
				)
				(justify left bottom)
				(hide yes)
			)
		)
		(property "Description" ""
			(at 106.68 96.52 0)
			(effects
				(font
					(size 1.27 1.27)
				)
			)
		)
		(property "Author" "Antmicro"
			(at 115.57 104.14 0)
			(effects
				(font
					(size 1.27 1.27)
					(thickness 0.15)
				)
				(justify left bottom)
				(hide yes)
			)
		)
		(property "License" "Apache-2.0"
			(at 115.57 106.68 0)
			(effects
				(font
					(size 1.27 1.27)
					(thickness 0.15)
				)
				(justify left bottom)
				(hide yes)
			)
		)
		(pin "1"
		)
		(instances
			(project "k410t-devboard"
				(path ""
					(reference "#PWR0214")
					(unit 1)
				)
			)
		)
	)
	(symbol
		(lib_id "antmicropower:+5V")
		(at 35.56 67.31 0)
		(unit 1)
		(exclude_from_sim no)
		(in_bom yes)
		(on_board yes)
		(dnp no)
		(property "Reference" "#PWR0224"
			(at 35.56 71.12 0)
			(effects
				(font
					(size 1.27 1.27)
				)
				(hide yes)
			)
		)
		(property "Value" "+5V"
			(at 35.56 63.5 0)
			(effects
				(font
					(size 1.27 1.27)
				)
			)
		)
		(property "Footprint" ""
			(at 35.56 67.31 0)
			(effects
				(font
					(size 1.27 1.27)
				)
				(hide yes)
			)
		)
		(property "Datasheet" ""
			(at 35.56 67.31 0)
			(effects
				(font
					(size 1.27 1.27)
				)
				(hide yes)
			)
		)
		(property "Description" ""
			(at 35.56 67.31 0)
			(effects
				(font
					(size 1.27 1.27)
				)
			)
		)
		(property "Author" "Antmicro"
			(at 50.8 74.93 0)
			(effects
				(font
					(size 1.27 1.27)
					(thickness 0.15)
				)
				(justify left bottom)
				(hide yes)
			)
		)
		(property "License" "Apache-2.0"
			(at 50.8 77.47 0)
			(effects
				(font
					(size 1.27 1.27)
					(thickness 0.15)
				)
				(justify left bottom)
				(hide yes)
			)
		)
		(pin "1"
		)
		(instances
			(project "k410t-devboard"
				(path ""
					(reference "#PWR0224")
					(unit 1)
				)
			)
		)
	)
	(symbol
		(lib_id "antmicroResistors0402:R_0R_0402")
		(at 331.47 76.2 270)
		(unit 1)
		(exclude_from_sim no)
		(in_bom no)
		(on_board yes)
		(dnp yes)
		(property "Reference" "R347"
			(at 332.74 77.47 90)
			(effects
				(font
					(size 1.27 1.27)
				)
				(justify left)
			)
		)
		(property "Value" "R_0R_0402"
			(at 318.77 96.52 0)
			(effects
				(font
					(size 1.27 1.27)
					(thickness 0.15)
				)
				(justify left bottom)
				(hide yes)
			)
		)
		(property "Footprint" "antmicro-footprints:R_0402_1005Metric"
			(at 316.23 96.52 0)
			(effects
				(font
					(size 1.27 1.27)
					(thickness 0.15)
				)
				(justify left bottom)
				(hide yes)
			)
		)
		(property "Datasheet" "https://industrial.panasonic.com/cdbs/www-data/pdf/RDA0000/AOA0000C301.pdf"
			(at 313.69 96.52 0)
			(effects
				(font
					(size 1.27 1.27)
					(thickness 0.15)
				)
				(justify left bottom)
				(hide yes)
			)
		)
		(property "Description" ""
			(at 331.47 76.2 0)
			(effects
				(font
					(size 1.27 1.27)
				)
			)
		)
		(property "Manufacturer" "Panasonic"
			(at 308.61 96.52 0)
			(effects
				(font
					(size 1.27 1.27)
					(thickness 0.15)
				)
				(justify left bottom)
				(hide yes)
			)
		)
		(property "MPN" "ERJ2GE0R00X"
			(at 311.15 96.52 0)
			(effects
				(font
					(size 1.27 1.27)
					(thickness 0.15)
				)
				(justify left bottom)
				(hide yes)
			)
		)
		(property "Val" "0R"
			(at 332.74 80.01 90)
			(effects
				(font
					(size 1.27 1.27)
					(thickness 0.15)
				)
				(justify left)
			)
		)
		(property "DNP" "DNP"
			(at 331.47 76.835 0)
			(effects
				(font
					(size 1.27 1.27)
				)
				(justify left)
			)
		)
		(property "License" "Apache-2.0"
			(at 306.07 96.52 0)
			(effects
				(font
					(size 1.27 1.27)
					(thickness 0.15)
				)
				(justify left bottom)
				(hide yes)
			)
		)
		(property "Author" "Antmicro"
			(at 303.53 96.52 0)
			(effects
				(font
					(size 1.27 1.27)
					(thickness 0.15)
				)
				(justify left bottom)
				(hide yes)
			)
		)
		(property "Tolerance" "~"
			(at 321.31 96.52 0)
			(effects
				(font
					(size 1.27 1.27)
				)
				(justify left bottom)
				(hide yes)
			)
		)
		(property "Current" "1A"
			(at 334.01 82.5499 90)
			(effects
				(font
					(size 1.27 1.27)
					(thickness 0.15)
				)
				(justify left)
				(hide yes)
			)
		)
		(pin "1"
		)
		(pin "2"
		)
		(instances
			(project "k410t-devboard"
				(path ""
					(reference "R347")
					(unit 1)
				)
			)
		)
	)
	(symbol
		(lib_id "antmicropower:GND")
		(at 151.13 218.44 0)
		(unit 1)
		(exclude_from_sim no)
		(in_bom yes)
		(on_board yes)
		(dnp no)
		(property "Reference" "#PWR0232"
			(at 151.13 224.79 0)
			(effects
				(font
					(size 1.27 1.27)
				)
				(hide yes)
			)
		)
		(property "Value" "GND"
			(at 151.13 222.25 0)
			(effects
				(font
					(size 1.27 1.27)
				)
			)
		)
		(property "Footprint" ""
			(at 160.02 226.06 0)
			(effects
				(font
					(size 1.27 1.27)
					(thickness 0.15)
				)
				(justify left bottom)
				(hide yes)
			)
		)
		(property "Datasheet" ""
			(at 160.02 231.14 0)
			(effects
				(font
					(size 1.27 1.27)
					(thickness 0.15)
				)
				(justify left bottom)
				(hide yes)
			)
		)
		(property "Description" ""
			(at 151.13 218.44 0)
			(effects
				(font
					(size 1.27 1.27)
				)
			)
		)
		(property "Author" "Antmicro"
			(at 160.02 226.06 0)
			(effects
				(font
					(size 1.27 1.27)
					(thickness 0.15)
				)
				(justify left bottom)
				(hide yes)
			)
		)
		(property "License" "Apache-2.0"
			(at 160.02 228.6 0)
			(effects
				(font
					(size 1.27 1.27)
					(thickness 0.15)
				)
				(justify left bottom)
				(hide yes)
			)
		)
		(pin "1"
		)
		(instances
			(project "k410t-devboard"
				(path ""
					(reference "#PWR0232")
					(unit 1)
				)
			)
		)
	)
	(symbol
		(lib_id "antmicroResistors0402:R_33R_0402")
		(at 340.36 185.42 0)
		(unit 1)
		(exclude_from_sim no)
		(in_bom yes)
		(on_board yes)
		(dnp no)
		(property "Reference" "R185"
			(at 347.98 184.15 0)
			(effects
				(font
					(size 1.27 1.27)
				)
			)
		)
		(property "Value" "R_33R_0402"
			(at 360.68 198.12 0)
			(effects
				(font
					(size 1.27 1.27)
					(thickness 0.15)
				)
				(justify left bottom)
				(hide yes)
			)
		)
		(property "Footprint" "antmicro-footprints:R_0402_1005Metric"
			(at 360.68 200.66 0)
			(effects
				(font
					(size 1.27 1.27)
					(thickness 0.15)
				)
				(justify left bottom)
				(hide yes)
			)
		)
		(property "Datasheet" "https://www.bourns.com/docs/product-datasheets/cr.pdf"
			(at 360.68 203.2 0)
			(effects
				(font
					(size 1.27 1.27)
					(thickness 0.15)
				)
				(justify left bottom)
				(hide yes)
			)
		)
		(property "Description" ""
			(at 340.36 185.42 0)
			(effects
				(font
					(size 1.27 1.27)
				)
			)
		)
		(property "Manufacturer" "Bourns"
			(at 360.68 208.28 0)
			(effects
				(font
					(size 1.27 1.27)
					(thickness 0.15)
				)
				(justify left bottom)
				(hide yes)
			)
		)
		(property "MPN" "CR0402-FX-33R0GLF"
			(at 360.68 205.74 0)
			(effects
				(font
					(size 1.27 1.27)
					(thickness 0.15)
				)
				(justify left bottom)
				(hide yes)
			)
		)
		(property "Val" "33R"
			(at 338.455 184.15 0)
			(effects
				(font
					(size 1.27 1.27)
					(thickness 0.15)
				)
			)
		)
		(property "License" "Apache-2.0"
			(at 360.68 210.82 0)
			(effects
				(font
					(size 1.27 1.27)
					(thickness 0.15)
				)
				(justify left bottom)
				(hide yes)
			)
		)
		(property "Author" "Antmicro"
			(at 360.68 213.36 0)
			(effects
				(font
					(size 1.27 1.27)
					(thickness 0.15)
				)
				(justify left bottom)
				(hide yes)
			)
		)
		(property "Tolerance" "1%"
			(at 360.68 195.58 0)
			(effects
				(font
					(size 1.27 1.27)
				)
				(justify left bottom)
				(hide yes)
			)
		)
		(pin "1"
		)
		(pin "2"
		)
		(instances
			(project "k410t-devboard"
				(path ""
					(reference "R185")
					(unit 1)
				)
			)
		)
	)
	(symbol
		(lib_id "antmicropower:GND")
		(at 387.35 246.38 0)
		(unit 1)
		(exclude_from_sim no)
		(in_bom yes)
		(on_board yes)
		(dnp no)
		(property "Reference" "#PWR0278"
			(at 387.35 252.73 0)
			(effects
				(font
					(size 1.27 1.27)
				)
				(hide yes)
			)
		)
		(property "Value" "GND"
			(at 387.35 250.19 0)
			(effects
				(font
					(size 1.27 1.27)
				)
			)
		)
		(property "Footprint" ""
			(at 396.24 254 0)
			(effects
				(font
					(size 1.27 1.27)
					(thickness 0.15)
				)
				(justify left bottom)
				(hide yes)
			)
		)
		(property "Datasheet" ""
			(at 396.24 259.08 0)
			(effects
				(font
					(size 1.27 1.27)
					(thickness 0.15)
				)
				(justify left bottom)
				(hide yes)
			)
		)
		(property "Description" ""
			(at 387.35 246.38 0)
			(effects
				(font
					(size 1.27 1.27)
				)
			)
		)
		(property "Author" "Antmicro"
			(at 396.24 254 0)
			(effects
				(font
					(size 1.27 1.27)
					(thickness 0.15)
				)
				(justify left bottom)
				(hide yes)
			)
		)
		(property "License" "Apache-2.0"
			(at 396.24 256.54 0)
			(effects
				(font
					(size 1.27 1.27)
					(thickness 0.15)
				)
				(justify left bottom)
				(hide yes)
			)
		)
		(pin "1"
		)
		(instances
			(project "k410t-devboard"
				(path ""
					(reference "#PWR0278")
					(unit 1)
				)
			)
		)
	)
	(symbol
		(lib_id "antmicropower:GND")
		(at 325.12 68.58 0)
		(unit 1)
		(exclude_from_sim no)
		(in_bom yes)
		(on_board yes)
		(dnp no)
		(property "Reference" "#PWR0267"
			(at 325.12 74.93 0)
			(effects
				(font
					(size 1.27 1.27)
				)
				(hide yes)
			)
		)
		(property "Value" "GND"
			(at 325.12 72.39 0)
			(effects
				(font
					(size 1.27 1.27)
				)
			)
		)
		(property "Footprint" ""
			(at 334.01 76.2 0)
			(effects
				(font
					(size 1.27 1.27)
					(thickness 0.15)
				)
				(justify left bottom)
				(hide yes)
			)
		)
		(property "Datasheet" ""
			(at 334.01 81.28 0)
			(effects
				(font
					(size 1.27 1.27)
					(thickness 0.15)
				)
				(justify left bottom)
				(hide yes)
			)
		)
		(property "Description" ""
			(at 325.12 68.58 0)
			(effects
				(font
					(size 1.27 1.27)
				)
			)
		)
		(property "Author" "Antmicro"
			(at 334.01 76.2 0)
			(effects
				(font
					(size 1.27 1.27)
					(thickness 0.15)
				)
				(justify left bottom)
				(hide yes)
			)
		)
		(property "License" "Apache-2.0"
			(at 334.01 78.74 0)
			(effects
				(font
					(size 1.27 1.27)
					(thickness 0.15)
				)
				(justify left bottom)
				(hide yes)
			)
		)
		(pin "1"
		)
		(instances
			(project "k410t-devboard"
				(path ""
					(reference "#PWR0267")
					(unit 1)
				)
			)
		)
	)
	(symbol
		(lib_id "antmicropower:GND")
		(at 64.77 143.51 0)
		(mirror y)
		(unit 1)
		(exclude_from_sim no)
		(in_bom yes)
		(on_board yes)
		(dnp no)
		(property "Reference" "#PWR0206"
			(at 64.77 149.86 0)
			(effects
				(font
					(size 1.27 1.27)
				)
				(hide yes)
			)
		)
		(property "Value" "GND"
			(at 64.77 147.32 0)
			(effects
				(font
					(size 1.27 1.27)
				)
			)
		)
		(property "Footprint" ""
			(at 55.88 151.13 0)
			(effects
				(font
					(size 1.27 1.27)
					(thickness 0.15)
				)
				(justify left bottom)
				(hide yes)
			)
		)
		(property "Datasheet" ""
			(at 55.88 156.21 0)
			(effects
				(font
					(size 1.27 1.27)
					(thickness 0.15)
				)
				(justify left bottom)
				(hide yes)
			)
		)
		(property "Description" ""
			(at 64.77 143.51 0)
			(effects
				(font
					(size 1.27 1.27)
				)
			)
		)
		(property "Author" "Antmicro"
			(at 55.88 151.13 0)
			(effects
				(font
					(size 1.27 1.27)
					(thickness 0.15)
				)
				(justify left bottom)
				(hide yes)
			)
		)
		(property "License" "Apache-2.0"
			(at 55.88 153.67 0)
			(effects
				(font
					(size 1.27 1.27)
					(thickness 0.15)
				)
				(justify left bottom)
				(hide yes)
			)
		)
		(pin "1"
		)
		(instances
			(project "k410t-devboard"
				(path ""
					(reference "#PWR0206")
					(unit 1)
				)
			)
		)
	)
	(symbol
		(lib_id "antmicroResistors0402:R_33R_0402")
		(at 300.99 58.42 0)
		(unit 1)
		(exclude_from_sim no)
		(in_bom yes)
		(on_board yes)
		(dnp no)
		(property "Reference" "R173"
			(at 308.61 57.15 0)
			(effects
				(font
					(size 1.27 1.27)
				)
			)
		)
		(property "Value" "R_33R_0402"
			(at 321.31 71.12 0)
			(effects
				(font
					(size 1.27 1.27)
					(thickness 0.15)
				)
				(justify left bottom)
				(hide yes)
			)
		)
		(property "Footprint" "antmicro-footprints:R_0402_1005Metric"
			(at 321.31 73.66 0)
			(effects
				(font
					(size 1.27 1.27)
					(thickness 0.15)
				)
				(justify left bottom)
				(hide yes)
			)
		)
		(property "Datasheet" "https://www.bourns.com/docs/product-datasheets/cr.pdf"
			(at 321.31 76.2 0)
			(effects
				(font
					(size 1.27 1.27)
					(thickness 0.15)
				)
				(justify left bottom)
				(hide yes)
			)
		)
		(property "Description" ""
			(at 300.99 58.42 0)
			(effects
				(font
					(size 1.27 1.27)
				)
			)
		)
		(property "Manufacturer" "Bourns"
			(at 321.31 81.28 0)
			(effects
				(font
					(size 1.27 1.27)
					(thickness 0.15)
				)
				(justify left bottom)
				(hide yes)
			)
		)
		(property "MPN" "CR0402-FX-33R0GLF"
			(at 321.31 78.74 0)
			(effects
				(font
					(size 1.27 1.27)
					(thickness 0.15)
				)
				(justify left bottom)
				(hide yes)
			)
		)
		(property "Val" "33R"
			(at 299.085 57.15 0)
			(effects
				(font
					(size 1.27 1.27)
					(thickness 0.15)
				)
			)
		)
		(property "License" "Apache-2.0"
			(at 321.31 83.82 0)
			(effects
				(font
					(size 1.27 1.27)
					(thickness 0.15)
				)
				(justify left bottom)
				(hide yes)
			)
		)
		(property "Author" "Antmicro"
			(at 321.31 86.36 0)
			(effects
				(font
					(size 1.27 1.27)
					(thickness 0.15)
				)
				(justify left bottom)
				(hide yes)
			)
		)
		(property "Tolerance" "1%"
			(at 321.31 68.58 0)
			(effects
				(font
					(size 1.27 1.27)
				)
				(justify left bottom)
				(hide yes)
			)
		)
		(pin "1"
		)
		(pin "2"
		)
		(instances
			(project "k410t-devboard"
				(path ""
					(reference "R173")
					(unit 1)
				)
			)
		)
	)
	(symbol
		(lib_id "antmicroCapacitors0402:C_22p_0402")
		(at 106.68 92.71 90)
		(unit 1)
		(exclude_from_sim no)
		(in_bom yes)
		(on_board yes)
		(dnp no)
		(property "Reference" "C220"
			(at 107.315 88.265 90)
			(effects
				(font
					(size 1.27 1.27)
				)
				(justify right)
			)
		)
		(property "Value" "C_22p_0402"
			(at 116.84 72.39 0)
			(effects
				(font
					(size 1.27 1.27)
					(thickness 0.15)
				)
				(justify left bottom)
				(hide yes)
			)
		)
		(property "Footprint" "antmicro-footprints:C_0402_1005Metric"
			(at 119.38 72.39 0)
			(effects
				(font
					(size 1.27 1.27)
					(thickness 0.15)
				)
				(justify left bottom)
				(hide yes)
			)
		)
		(property "Datasheet" "https://www.yageo.com/en/Chart/Download/pdf/CC0402JRNPO9BN220"
			(at 121.92 72.39 0)
			(effects
				(font
					(size 1.27 1.27)
					(thickness 0.15)
				)
				(justify left bottom)
				(hide yes)
			)
		)
		(property "Description" ""
			(at 106.68 92.71 0)
			(effects
				(font
					(size 1.27 1.27)
				)
			)
		)
		(property "Manufacturer" "YAGEO"
			(at 127 72.39 0)
			(effects
				(font
					(size 1.27 1.27)
					(thickness 0.15)
				)
				(justify left bottom)
				(hide yes)
			)
		)
		(property "MPN" "CC0402JRNPO9BN220"
			(at 124.46 72.39 0)
			(effects
				(font
					(size 1.27 1.27)
					(thickness 0.15)
				)
				(justify left bottom)
				(hide yes)
			)
		)
		(property "Val" "22p"
			(at 107.315 92.075 90)
			(effects
				(font
					(size 1.27 1.27)
					(thickness 0.15)
				)
				(justify right)
			)
		)
		(property "License" "Apache-2.0"
			(at 129.54 72.39 0)
			(effects
				(font
					(size 1.27 1.27)
					(thickness 0.15)
				)
				(justify left bottom)
				(hide yes)
			)
		)
		(property "Author" "Antmicro"
			(at 132.08 72.39 0)
			(effects
				(font
					(size 1.27 1.27)
					(thickness 0.15)
				)
				(justify left bottom)
				(hide yes)
			)
		)
		(property "Voltage" ""
			(at 134.62 72.39 0)
			(effects
				(font
					(size 1.27 1.27)
				)
				(justify left bottom)
				(hide yes)
			)
		)
		(property "Dielectric" ""
			(at 137.16 72.39 0)
			(effects
				(font
					(size 1.27 1.27)
				)
				(justify left bottom)
				(hide yes)
			)
		)
		(pin "1"
		)
		(pin "2"
		)
		(instances
			(project "k410t-devboard"
				(path ""
					(reference "C220")
					(unit 1)
				)
			)
		)
	)
	(symbol
		(lib_id "antmicroCapacitors0402:C_10u_0402")
		(at 115.57 133.35 90)
		(unit 1)
		(exclude_from_sim no)
		(in_bom yes)
		(on_board yes)
		(dnp no)
		(property "Reference" "C229"
			(at 116.205 128.905 90)
			(effects
				(font
					(size 1.27 1.27)
				)
				(justify right)
			)
		)
		(property "Value" "C_10u_0402"
			(at 125.73 113.03 0)
			(effects
				(font
					(size 1.27 1.27)
					(thickness 0.15)
				)
				(justify left bottom)
				(hide yes)
			)
		)
		(property "Footprint" "antmicro-footprints:C_0402_1005Metric"
			(at 128.27 113.03 0)
			(effects
				(font
					(size 1.27 1.27)
					(thickness 0.15)
				)
				(justify left bottom)
				(hide yes)
			)
		)
		(property "Datasheet" "https://www.yageo.com/en/Chart/Download/pdf/CC0402MRX5R5BB106"
			(at 130.81 113.03 0)
			(effects
				(font
					(size 1.27 1.27)
					(thickness 0.15)
				)
				(justify left bottom)
				(hide yes)
			)
		)
		(property "Description" ""
			(at 115.57 133.35 0)
			(effects
				(font
					(size 1.27 1.27)
				)
			)
		)
		(property "Manufacturer" "YAGEO"
			(at 135.89 113.03 0)
			(effects
				(font
					(size 1.27 1.27)
					(thickness 0.15)
				)
				(justify left bottom)
				(hide yes)
			)
		)
		(property "MPN" "CC0402MRX5R5BB106"
			(at 133.35 113.03 0)
			(effects
				(font
					(size 1.27 1.27)
					(thickness 0.15)
				)
				(justify left bottom)
				(hide yes)
			)
		)
		(property "Val" "10u"
			(at 116.205 132.715 90)
			(effects
				(font
					(size 1.27 1.27)
					(thickness 0.15)
				)
				(justify right)
			)
		)
		(property "License" "Apache-2.0"
			(at 138.43 113.03 0)
			(effects
				(font
					(size 1.27 1.27)
					(thickness 0.15)
				)
				(justify left bottom)
				(hide yes)
			)
		)
		(property "Author" "Antmicro"
			(at 140.97 113.03 0)
			(effects
				(font
					(size 1.27 1.27)
					(thickness 0.15)
				)
				(justify left bottom)
				(hide yes)
			)
		)
		(property "Voltage" ""
			(at 143.51 113.03 0)
			(effects
				(font
					(size 1.27 1.27)
				)
				(justify left bottom)
				(hide yes)
			)
		)
		(property "Dielectric" ""
			(at 146.05 113.03 0)
			(effects
				(font
					(size 1.27 1.27)
				)
				(justify left bottom)
				(hide yes)
			)
		)
		(pin "1"
		)
		(pin "2"
		)
		(instances
			(project "k410t-devboard"
				(path ""
					(reference "C229")
					(unit 1)
				)
			)
		)
	)
	(symbol
		(lib_id "antmicroCapacitors0402:C_100n_0402")
		(at 321.31 245.11 90)
		(unit 1)
		(exclude_from_sim no)
		(in_bom yes)
		(on_board yes)
		(dnp no)
		(property "Reference" "C401"
			(at 321.945 240.665 90)
			(effects
				(font
					(size 1.27 1.27)
				)
				(justify right)
			)
		)
		(property "Value" "C_100n_0402"
			(at 331.47 224.79 0)
			(effects
				(font
					(size 1.27 1.27)
					(thickness 0.15)
				)
				(justify left bottom)
				(hide yes)
			)
		)
		(property "Footprint" "antmicro-footprints:C_0402_1005Metric"
			(at 334.01 224.79 0)
			(effects
				(font
					(size 1.27 1.27)
					(thickness 0.15)
				)
				(justify left bottom)
				(hide yes)
			)
		)
		(property "Datasheet" "https://www.murata.com/products/productdetail?partno=GRM155R61H104KE14%23"
			(at 336.55 224.79 0)
			(effects
				(font
					(size 1.27 1.27)
					(thickness 0.15)
				)
				(justify left bottom)
				(hide yes)
			)
		)
		(property "Description" ""
			(at 321.31 245.11 0)
			(effects
				(font
					(size 1.27 1.27)
				)
			)
		)
		(property "Manufacturer" "Murata"
			(at 341.63 224.79 0)
			(effects
				(font
					(size 1.27 1.27)
					(thickness 0.15)
				)
				(justify left bottom)
				(hide yes)
			)
		)
		(property "MPN" "GRM155R61H104KE14D"
			(at 339.09 224.79 0)
			(effects
				(font
					(size 1.27 1.27)
					(thickness 0.15)
				)
				(justify left bottom)
				(hide yes)
			)
		)
		(property "Val" "100n"
			(at 321.945 244.475 90)
			(effects
				(font
					(size 1.27 1.27)
					(thickness 0.15)
				)
				(justify right)
			)
		)
		(property "License" "Apache-2.0"
			(at 344.17 224.79 0)
			(effects
				(font
					(size 1.27 1.27)
					(thickness 0.15)
				)
				(justify left bottom)
				(hide yes)
			)
		)
		(property "Author" "Antmicro"
			(at 346.71 224.79 0)
			(effects
				(font
					(size 1.27 1.27)
					(thickness 0.15)
				)
				(justify left bottom)
				(hide yes)
			)
		)
		(property "Voltage" "50V"
			(at 349.25 224.79 0)
			(effects
				(font
					(size 1.27 1.27)
				)
				(justify left bottom)
				(hide yes)
			)
		)
		(property "Dielectric" "X5R"
			(at 351.79 224.79 0)
			(effects
				(font
					(size 1.27 1.27)
				)
				(justify left bottom)
				(hide yes)
			)
		)
		(pin "1"
		)
		(pin "2"
		)
		(instances
			(project "k410t-devboard"
				(path ""
					(reference "C401")
					(unit 1)
				)
			)
		)
	)
	(symbol
		(lib_id "antmicropower:GND")
		(at 312.42 189.23 0)
		(unit 1)
		(exclude_from_sim no)
		(in_bom yes)
		(on_board yes)
		(dnp no)
		(property "Reference" "#PWR0263"
			(at 312.42 195.58 0)
			(effects
				(font
					(size 1.27 1.27)
				)
				(hide yes)
			)
		)
		(property "Value" "GND"
			(at 312.42 193.04 0)
			(effects
				(font
					(size 1.27 1.27)
				)
			)
		)
		(property "Footprint" ""
			(at 321.31 196.85 0)
			(effects
				(font
					(size 1.27 1.27)
					(thickness 0.15)
				)
				(justify left bottom)
				(hide yes)
			)
		)
		(property "Datasheet" ""
			(at 321.31 201.93 0)
			(effects
				(font
					(size 1.27 1.27)
					(thickness 0.15)
				)
				(justify left bottom)
				(hide yes)
			)
		)
		(property "Description" ""
			(at 312.42 189.23 0)
			(effects
				(font
					(size 1.27 1.27)
				)
			)
		)
		(property "Author" "Antmicro"
			(at 321.31 196.85 0)
			(effects
				(font
					(size 1.27 1.27)
					(thickness 0.15)
				)
				(justify left bottom)
				(hide yes)
			)
		)
		(property "License" "Apache-2.0"
			(at 321.31 199.39 0)
			(effects
				(font
					(size 1.27 1.27)
					(thickness 0.15)
				)
				(justify left bottom)
				(hide yes)
			)
		)
		(pin "1"
		)
		(instances
			(project "k410t-devboard"
				(path ""
					(reference "#PWR0263")
					(unit 1)
				)
			)
		)
	)
	(symbol
		(lib_id "antmicroResistors0402:R_10k_0402")
		(at 392.43 48.26 0)
		(mirror x)
		(unit 1)
		(exclude_from_sim no)
		(in_bom yes)
		(on_board yes)
		(dnp no)
		(property "Reference" "R195"
			(at 400.05 46.99 0)
			(effects
				(font
					(size 1.27 1.27)
				)
			)
		)
		(property "Value" "R_10k_0402"
			(at 412.75 35.56 0)
			(effects
				(font
					(size 1.27 1.27)
					(thickness 0.15)
				)
				(justify left bottom)
				(hide yes)
			)
		)
		(property "Footprint" "antmicro-footprints:R_0402_1005Metric"
			(at 412.75 33.02 0)
			(effects
				(font
					(size 1.27 1.27)
					(thickness 0.15)
				)
				(justify left bottom)
				(hide yes)
			)
		)
		(property "Datasheet" "https://www.bourns.com/docs/product-datasheets/cr.pdf"
			(at 412.75 30.48 0)
			(effects
				(font
					(size 1.27 1.27)
					(thickness 0.15)
				)
				(justify left bottom)
				(hide yes)
			)
		)
		(property "Description" ""
			(at 392.43 48.26 0)
			(effects
				(font
					(size 1.27 1.27)
				)
			)
		)
		(property "Manufacturer" "Bourns"
			(at 412.75 25.4 0)
			(effects
				(font
					(size 1.27 1.27)
					(thickness 0.15)
				)
				(justify left bottom)
				(hide yes)
			)
		)
		(property "MPN" "CR0402-FX-1002GLF"
			(at 412.75 27.94 0)
			(effects
				(font
					(size 1.27 1.27)
					(thickness 0.15)
				)
				(justify left bottom)
				(hide yes)
			)
		)
		(property "Val" "10k"
			(at 390.525 46.99 0)
			(effects
				(font
					(size 1.27 1.27)
					(thickness 0.15)
				)
			)
		)
		(property "License" "Apache-2.0"
			(at 412.75 22.86 0)
			(effects
				(font
					(size 1.27 1.27)
					(thickness 0.15)
				)
				(justify left bottom)
				(hide yes)
			)
		)
		(property "Author" "Antmicro"
			(at 412.75 20.32 0)
			(effects
				(font
					(size 1.27 1.27)
					(thickness 0.15)
				)
				(justify left bottom)
				(hide yes)
			)
		)
		(property "Tolerance" "1%"
			(at 412.75 38.1 0)
			(effects
				(font
					(size 1.27 1.27)
				)
				(justify left bottom)
				(hide yes)
			)
		)
		(pin "1"
		)
		(pin "2"
		)
		(instances
			(project "k410t-devboard"
				(path ""
					(reference "R195")
					(unit 1)
				)
			)
		)
	)
	(symbol
		(lib_id "antmicropower:GND")
		(at 360.68 101.6 0)
		(unit 1)
		(exclude_from_sim no)
		(in_bom yes)
		(on_board yes)
		(dnp no)
		(property "Reference" "#PWR0273"
			(at 360.68 107.95 0)
			(effects
				(font
					(size 1.27 1.27)
				)
				(hide yes)
			)
		)
		(property "Value" "GND"
			(at 360.68 105.41 0)
			(effects
				(font
					(size 1.27 1.27)
				)
			)
		)
		(property "Footprint" ""
			(at 369.57 109.22 0)
			(effects
				(font
					(size 1.27 1.27)
					(thickness 0.15)
				)
				(justify left bottom)
				(hide yes)
			)
		)
		(property "Datasheet" ""
			(at 369.57 114.3 0)
			(effects
				(font
					(size 1.27 1.27)
					(thickness 0.15)
				)
				(justify left bottom)
				(hide yes)
			)
		)
		(property "Description" ""
			(at 360.68 101.6 0)
			(effects
				(font
					(size 1.27 1.27)
				)
			)
		)
		(property "Author" "Antmicro"
			(at 369.57 109.22 0)
			(effects
				(font
					(size 1.27 1.27)
					(thickness 0.15)
				)
				(justify left bottom)
				(hide yes)
			)
		)
		(property "License" "Apache-2.0"
			(at 369.57 111.76 0)
			(effects
				(font
					(size 1.27 1.27)
					(thickness 0.15)
				)
				(justify left bottom)
				(hide yes)
			)
		)
		(pin "1"
		)
		(instances
			(project "k410t-devboard"
				(path ""
					(reference "#PWR0273")
					(unit 1)
				)
			)
		)
	)
	(symbol
		(lib_id "antmicroCapacitors0402:C_100n_0402")
		(at 157.48 33.02 90)
		(unit 1)
		(exclude_from_sim no)
		(in_bom yes)
		(on_board yes)
		(dnp no)
		(property "Reference" "C231"
			(at 158.115 28.575 90)
			(effects
				(font
					(size 1.27 1.27)
				)
				(justify right)
			)
		)
		(property "Value" "C_100n_0402"
			(at 167.64 12.7 0)
			(effects
				(font
					(size 1.27 1.27)
					(thickness 0.15)
				)
				(justify left bottom)
				(hide yes)
			)
		)
		(property "Footprint" "antmicro-footprints:C_0402_1005Metric"
			(at 170.18 12.7 0)
			(effects
				(font
					(size 1.27 1.27)
					(thickness 0.15)
				)
				(justify left bottom)
				(hide yes)
			)
		)
		(property "Datasheet" "https://www.murata.com/products/productdetail?partno=GRM155R61H104KE14%23"
			(at 172.72 12.7 0)
			(effects
				(font
					(size 1.27 1.27)
					(thickness 0.15)
				)
				(justify left bottom)
				(hide yes)
			)
		)
		(property "Description" ""
			(at 157.48 33.02 0)
			(effects
				(font
					(size 1.27 1.27)
				)
			)
		)
		(property "Manufacturer" "Murata"
			(at 177.8 12.7 0)
			(effects
				(font
					(size 1.27 1.27)
					(thickness 0.15)
				)
				(justify left bottom)
				(hide yes)
			)
		)
		(property "MPN" "GRM155R61H104KE14D"
			(at 175.26 12.7 0)
			(effects
				(font
					(size 1.27 1.27)
					(thickness 0.15)
				)
				(justify left bottom)
				(hide yes)
			)
		)
		(property "Val" "100n"
			(at 158.115 32.385 90)
			(effects
				(font
					(size 1.27 1.27)
					(thickness 0.15)
				)
				(justify right)
			)
		)
		(property "License" "Apache-2.0"
			(at 180.34 12.7 0)
			(effects
				(font
					(size 1.27 1.27)
					(thickness 0.15)
				)
				(justify left bottom)
				(hide yes)
			)
		)
		(property "Author" "Antmicro"
			(at 182.88 12.7 0)
			(effects
				(font
					(size 1.27 1.27)
					(thickness 0.15)
				)
				(justify left bottom)
				(hide yes)
			)
		)
		(property "Voltage" "50V"
			(at 185.42 12.7 0)
			(effects
				(font
					(size 1.27 1.27)
				)
				(justify left bottom)
				(hide yes)
			)
		)
		(property "Dielectric" "X5R"
			(at 187.96 12.7 0)
			(effects
				(font
					(size 1.27 1.27)
				)
				(justify left bottom)
				(hide yes)
			)
		)
		(pin "1"
		)
		(pin "2"
		)
		(instances
			(project "k410t-devboard"
				(path ""
					(reference "C231")
					(unit 1)
				)
			)
		)
	)
	(symbol
		(lib_id "antmicropower:+5V")
		(at 331.47 74.93 0)
		(unit 1)
		(exclude_from_sim no)
		(in_bom yes)
		(on_board yes)
		(dnp no)
		(property "Reference" "#PWR0465"
			(at 331.47 78.74 0)
			(effects
				(font
					(size 1.27 1.27)
				)
				(hide yes)
			)
		)
		(property "Value" "+5V"
			(at 331.47 71.12 0)
			(effects
				(font
					(size 1.27 1.27)
				)
			)
		)
		(property "Footprint" ""
			(at 331.47 74.93 0)
			(effects
				(font
					(size 1.27 1.27)
				)
				(hide yes)
			)
		)
		(property "Datasheet" ""
			(at 331.47 74.93 0)
			(effects
				(font
					(size 1.27 1.27)
				)
				(hide yes)
			)
		)
		(property "Description" ""
			(at 331.47 74.93 0)
			(effects
				(font
					(size 1.27 1.27)
				)
			)
		)
		(property "Author" "Antmicro"
			(at 346.71 82.55 0)
			(effects
				(font
					(size 1.27 1.27)
					(thickness 0.15)
				)
				(justify left bottom)
				(hide yes)
			)
		)
		(property "License" "Apache-2.0"
			(at 346.71 85.09 0)
			(effects
				(font
					(size 1.27 1.27)
					(thickness 0.15)
				)
				(justify left bottom)
				(hide yes)
			)
		)
		(pin "1"
		)
		(instances
			(project "k410t-devboard"
				(path ""
					(reference "#PWR0465")
					(unit 1)
				)
			)
		)
	)
	(symbol
		(lib_id "antmicropower:PWR_FLAG")
		(at 63.5 162.56 0)
		(unit 1)
		(exclude_from_sim no)
		(in_bom yes)
		(on_board yes)
		(dnp no)
		(property "Reference" "#FLG04"
			(at 63.5 160.655 0)
			(effects
				(font
					(size 1.27 1.27)
				)
				(hide yes)
			)
		)
		(property "Value" "PWR_FLAG"
			(at 63.5 158.75 0)
			(effects
				(font
					(size 1.27 1.27)
				)
			)
		)
		(property "Footprint" ""
			(at 63.5 162.56 0)
			(effects
				(font
					(size 1.27 1.27)
				)
				(hide yes)
			)
		)
		(property "Datasheet" ""
			(at 63.5 162.56 0)
			(effects
				(font
					(size 1.27 1.27)
				)
				(hide yes)
			)
		)
		(property "Description" ""
			(at 63.5 162.56 0)
			(effects
				(font
					(size 1.27 1.27)
				)
			)
		)
		(pin "1"
		)
		(instances
			(project "k410t-devboard"
				(path ""
					(reference "#FLG04")
					(unit 1)
				)
			)
		)
	)
	(symbol
		(lib_id "antmicroInterfaceControllers:TUSB1106RSVR")
		(at 327.66 40.64 0)
		(unit 1)
		(exclude_from_sim no)
		(in_bom yes)
		(on_board yes)
		(dnp no)
		(fields_autoplaced yes)
		(property "Reference" "U25"
			(at 339.09 33.02 0)
			(effects
				(font
					(size 1.27 1.27)
				)
			)
		)
		(property "Value" "TUSB1106RSVR"
			(at 339.09 35.56 0)
			(effects
				(font
					(size 1.27 1.27)
					(thickness 0.15)
				)
				(hide yes)
			)
		)
		(property "Footprint" "antmicro-footprints:UQFN-16-1.8x2.6mm_P0.4mm_Texas_RSV0016A"
			(at 364.49 49.53 0)
			(effects
				(font
					(size 1.27 1.27)
					(thickness 0.15)
				)
				(justify left bottom)
				(hide yes)
			)
		)
		(property "Datasheet" "https://www.ti.com/lit/ds/symlink/tusb1106.pdf?ts=1672125307635&ref_url=https%253A%252F%252Fwww.ti.com%252Fproduct%252FTUSB1106%252Fpart-details%252FTUSB1106RTZR"
			(at 364.49 52.07 0)
			(effects
				(font
					(size 1.27 1.27)
					(thickness 0.15)
				)
				(justify left bottom)
				(hide yes)
			)
		)
		(property "Description" ""
			(at 327.66 40.64 0)
			(effects
				(font
					(size 1.27 1.27)
				)
			)
		)
		(property "MPN" "TUSB1106RSVR"
			(at 339.09 35.56 0)
			(effects
				(font
					(size 1.27 1.27)
					(thickness 0.15)
				)
			)
		)
		(property "Manufacturer" "Texas Instruments"
			(at 364.49 57.15 0)
			(effects
				(font
					(size 1.27 1.27)
					(thickness 0.15)
				)
				(justify left bottom)
				(hide yes)
			)
		)
		(property "Author" "Antmicro"
			(at 364.49 59.69 0)
			(effects
				(font
					(size 1.27 1.27)
					(thickness 0.15)
				)
				(justify left bottom)
				(hide yes)
			)
		)
		(property "License" "Apache-2.0"
			(at 364.49 62.23 0)
			(effects
				(font
					(size 1.27 1.27)
					(thickness 0.15)
				)
				(justify left bottom)
				(hide yes)
			)
		)
		(pin "1"
		)
		(pin "10"
		)
		(pin "11"
		)
		(pin "12"
		)
		(pin "13"
		)
		(pin "14"
		)
		(pin "15"
		)
		(pin "16"
		)
		(pin "2"
		)
		(pin "3"
		)
		(pin "4"
		)
		(pin "5"
		)
		(pin "6"
		)
		(pin "7"
		)
		(pin "8"
		)
		(pin "9"
		)
		(instances
			(project "k410t-devboard"
				(path ""
					(reference "U25")
					(unit 1)
				)
			)
		)
	)
	(symbol
		(lib_id "antmicropower:+3.3V")
		(at 149.86 24.13 0)
		(unit 1)
		(exclude_from_sim no)
		(in_bom yes)
		(on_board yes)
		(dnp no)
		(property "Reference" "#PWR0199"
			(at 149.86 27.94 0)
			(effects
				(font
					(size 1.27 1.27)
				)
				(hide yes)
			)
		)
		(property "Value" "+3V3"
			(at 149.86 20.32 0)
			(effects
				(font
					(size 1.27 1.27)
				)
			)
		)
		(property "Footprint" ""
			(at 149.86 24.13 0)
			(effects
				(font
					(size 1.27 1.27)
				)
				(hide yes)
			)
		)
		(property "Datasheet" ""
			(at 149.86 24.13 0)
			(effects
				(font
					(size 1.27 1.27)
				)
				(hide yes)
			)
		)
		(property "Description" ""
			(at 149.86 24.13 0)
			(effects
				(font
					(size 1.27 1.27)
				)
			)
		)
		(pin "1"
		)
		(instances
			(project "k410t-devboard"
				(path ""
					(reference "#PWR0199")
					(unit 1)
				)
			)
		)
	)
	(symbol
		(lib_id "antmicropower:GND")
		(at 165.1 90.17 0)
		(unit 1)
		(exclude_from_sim no)
		(in_bom yes)
		(on_board yes)
		(dnp no)
		(fields_autoplaced yes)
		(property "Reference" "#PWR0241"
			(at 165.1 96.52 0)
			(effects
				(font
					(size 1.27 1.27)
				)
				(hide yes)
			)
		)
		(property "Value" "GND"
			(at 165.1 95.25 0)
			(effects
				(font
					(size 1.27 1.27)
				)
			)
		)
		(property "Footprint" ""
			(at 173.99 97.79 0)
			(effects
				(font
					(size 1.27 1.27)
					(thickness 0.15)
				)
				(justify left bottom)
				(hide yes)
			)
		)
		(property "Datasheet" ""
			(at 173.99 102.87 0)
			(effects
				(font
					(size 1.27 1.27)
					(thickness 0.15)
				)
				(justify left bottom)
				(hide yes)
			)
		)
		(property "Description" ""
			(at 165.1 90.17 0)
			(effects
				(font
					(size 1.27 1.27)
				)
			)
		)
		(property "Author" "Antmicro"
			(at 173.99 97.79 0)
			(effects
				(font
					(size 1.27 1.27)
					(thickness 0.15)
				)
				(justify left bottom)
				(hide yes)
			)
		)
		(property "License" "Apache-2.0"
			(at 173.99 100.33 0)
			(effects
				(font
					(size 1.27 1.27)
					(thickness 0.15)
				)
				(justify left bottom)
				(hide yes)
			)
		)
		(pin "1"
		)
		(instances
			(project "k410t-devboard"
				(path ""
					(reference "#PWR0241")
					(unit 1)
				)
			)
		)
	)
	(symbol
		(lib_id "antmicroResistors0402:R_33R_0402")
		(at 300.99 60.96 0)
		(unit 1)
		(exclude_from_sim no)
		(in_bom yes)
		(on_board yes)
		(dnp no)
		(property "Reference" "R174"
			(at 308.61 59.69 0)
			(effects
				(font
					(size 1.27 1.27)
				)
			)
		)
		(property "Value" "R_33R_0402"
			(at 321.31 73.66 0)
			(effects
				(font
					(size 1.27 1.27)
					(thickness 0.15)
				)
				(justify left bottom)
				(hide yes)
			)
		)
		(property "Footprint" "antmicro-footprints:R_0402_1005Metric"
			(at 321.31 76.2 0)
			(effects
				(font
					(size 1.27 1.27)
					(thickness 0.15)
				)
				(justify left bottom)
				(hide yes)
			)
		)
		(property "Datasheet" "https://www.bourns.com/docs/product-datasheets/cr.pdf"
			(at 321.31 78.74 0)
			(effects
				(font
					(size 1.27 1.27)
					(thickness 0.15)
				)
				(justify left bottom)
				(hide yes)
			)
		)
		(property "Description" ""
			(at 300.99 60.96 0)
			(effects
				(font
					(size 1.27 1.27)
				)
			)
		)
		(property "Manufacturer" "Bourns"
			(at 321.31 83.82 0)
			(effects
				(font
					(size 1.27 1.27)
					(thickness 0.15)
				)
				(justify left bottom)
				(hide yes)
			)
		)
		(property "MPN" "CR0402-FX-33R0GLF"
			(at 321.31 81.28 0)
			(effects
				(font
					(size 1.27 1.27)
					(thickness 0.15)
				)
				(justify left bottom)
				(hide yes)
			)
		)
		(property "Val" "33R"
			(at 299.085 59.69 0)
			(effects
				(font
					(size 1.27 1.27)
					(thickness 0.15)
				)
			)
		)
		(property "License" "Apache-2.0"
			(at 321.31 86.36 0)
			(effects
				(font
					(size 1.27 1.27)
					(thickness 0.15)
				)
				(justify left bottom)
				(hide yes)
			)
		)
		(property "Author" "Antmicro"
			(at 321.31 88.9 0)
			(effects
				(font
					(size 1.27 1.27)
					(thickness 0.15)
				)
				(justify left bottom)
				(hide yes)
			)
		)
		(property "Tolerance" "1%"
			(at 321.31 71.12 0)
			(effects
				(font
					(size 1.27 1.27)
				)
				(justify left bottom)
				(hide yes)
			)
		)
		(pin "1"
		)
		(pin "2"
		)
		(instances
			(project "k410t-devboard"
				(path ""
					(reference "R174")
					(unit 1)
				)
			)
		)
	)
	(symbol
		(lib_id "antmicropower:GND")
		(at 104.14 176.53 0)
		(mirror y)
		(unit 1)
		(exclude_from_sim no)
		(in_bom yes)
		(on_board yes)
		(dnp no)
		(property "Reference" "#PWR0213"
			(at 104.14 182.88 0)
			(effects
				(font
					(size 1.27 1.27)
				)
				(hide yes)
			)
		)
		(property "Value" "GND"
			(at 104.14 180.34 0)
			(effects
				(font
					(size 1.27 1.27)
				)
			)
		)
		(property "Footprint" ""
			(at 95.25 184.15 0)
			(effects
				(font
					(size 1.27 1.27)
					(thickness 0.15)
				)
				(justify left bottom)
				(hide yes)
			)
		)
		(property "Datasheet" ""
			(at 95.25 189.23 0)
			(effects
				(font
					(size 1.27 1.27)
					(thickness 0.15)
				)
				(justify left bottom)
				(hide yes)
			)
		)
		(property "Description" ""
			(at 104.14 176.53 0)
			(effects
				(font
					(size 1.27 1.27)
				)
			)
		)
		(property "Author" "Antmicro"
			(at 95.25 184.15 0)
			(effects
				(font
					(size 1.27 1.27)
					(thickness 0.15)
				)
				(justify left bottom)
				(hide yes)
			)
		)
		(property "License" "Apache-2.0"
			(at 95.25 186.69 0)
			(effects
				(font
					(size 1.27 1.27)
					(thickness 0.15)
				)
				(justify left bottom)
				(hide yes)
			)
		)
		(pin "1"
		)
		(instances
			(project "k410t-devboard"
				(path ""
					(reference "#PWR0213")
					(unit 1)
				)
			)
		)
	)
	(symbol
		(lib_id "antmicroResistors0402:R_33R_0402")
		(at 238.76 186.69 0)
		(unit 1)
		(exclude_from_sim no)
		(in_bom yes)
		(on_board yes)
		(dnp no)
		(property "Reference" "R161"
			(at 243.84 185.42 0)
			(effects
				(font
					(size 1.27 1.27)
				)
				(justify left)
			)
		)
		(property "Value" "R_33R_0402"
			(at 259.08 199.39 0)
			(effects
				(font
					(size 1.27 1.27)
					(thickness 0.15)
				)
				(justify left bottom)
				(hide yes)
			)
		)
		(property "Footprint" "antmicro-footprints:R_0402_1005Metric"
			(at 259.08 201.93 0)
			(effects
				(font
					(size 1.27 1.27)
					(thickness 0.15)
				)
				(justify left bottom)
				(hide yes)
			)
		)
		(property "Datasheet" "https://www.bourns.com/docs/product-datasheets/cr.pdf"
			(at 259.08 204.47 0)
			(effects
				(font
					(size 1.27 1.27)
					(thickness 0.15)
				)
				(justify left bottom)
				(hide yes)
			)
		)
		(property "Description" ""
			(at 238.76 186.69 0)
			(effects
				(font
					(size 1.27 1.27)
				)
			)
		)
		(property "Manufacturer" "Bourns"
			(at 259.08 209.55 0)
			(effects
				(font
					(size 1.27 1.27)
					(thickness 0.15)
				)
				(justify left bottom)
				(hide yes)
			)
		)
		(property "MPN" "CR0402-FX-33R0GLF"
			(at 259.08 207.01 0)
			(effects
				(font
					(size 1.27 1.27)
					(thickness 0.15)
				)
				(justify left bottom)
				(hide yes)
			)
		)
		(property "Val" "33R"
			(at 234.95 186.69 0)
			(effects
				(font
					(size 1.27 1.27)
					(thickness 0.15)
				)
				(justify left bottom)
			)
		)
		(property "License" "Apache-2.0"
			(at 259.08 212.09 0)
			(effects
				(font
					(size 1.27 1.27)
					(thickness 0.15)
				)
				(justify left bottom)
				(hide yes)
			)
		)
		(property "Author" "Antmicro"
			(at 259.08 214.63 0)
			(effects
				(font
					(size 1.27 1.27)
					(thickness 0.15)
				)
				(justify left bottom)
				(hide yes)
			)
		)
		(property "Tolerance" "1%"
			(at 259.08 196.85 0)
			(effects
				(font
					(size 1.27 1.27)
				)
				(justify left bottom)
				(hide yes)
			)
		)
		(pin "1"
		)
		(pin "2"
		)
		(instances
			(project "k410t-devboard"
				(path ""
					(reference "R161")
					(unit 1)
				)
			)
		)
	)
	(symbol
		(lib_id "antmicroResistors0402:R_0R_0402")
		(at 342.9 96.52 180)
		(unit 1)
		(exclude_from_sim no)
		(in_bom yes)
		(on_board yes)
		(dnp no)
		(property "Reference" "R349"
			(at 345.44 95.25 0)
			(effects
				(font
					(size 1.27 1.27)
				)
			)
		)
		(property "Value" "R_0R_0402"
			(at 322.58 83.82 0)
			(effects
				(font
					(size 1.27 1.27)
					(thickness 0.15)
				)
				(justify left bottom)
				(hide yes)
			)
		)
		(property "Footprint" "antmicro-footprints:R_0402_1005Metric"
			(at 322.58 81.28 0)
			(effects
				(font
					(size 1.27 1.27)
					(thickness 0.15)
				)
				(justify left bottom)
				(hide yes)
			)
		)
		(property "Datasheet" "https://industrial.panasonic.com/cdbs/www-data/pdf/RDA0000/AOA0000C301.pdf"
			(at 322.58 78.74 0)
			(effects
				(font
					(size 1.27 1.27)
					(thickness 0.15)
				)
				(justify left bottom)
				(hide yes)
			)
		)
		(property "Description" ""
			(at 342.9 96.52 0)
			(effects
				(font
					(size 1.27 1.27)
				)
			)
		)
		(property "Manufacturer" "Panasonic"
			(at 322.58 73.66 0)
			(effects
				(font
					(size 1.27 1.27)
					(thickness 0.15)
				)
				(justify left bottom)
				(hide yes)
			)
		)
		(property "MPN" "ERJ2GE0R00X"
			(at 322.58 76.2 0)
			(effects
				(font
					(size 1.27 1.27)
					(thickness 0.15)
				)
				(justify left bottom)
				(hide yes)
			)
		)
		(property "Val" "0R"
			(at 336.55 95.25 0)
			(effects
				(font
					(size 1.27 1.27)
					(thickness 0.15)
				)
			)
		)
		(property "License" "Apache-2.0"
			(at 322.58 71.12 0)
			(effects
				(font
					(size 1.27 1.27)
					(thickness 0.15)
				)
				(justify left bottom)
				(hide yes)
			)
		)
		(property "Author" "Antmicro"
			(at 322.58 68.58 0)
			(effects
				(font
					(size 1.27 1.27)
					(thickness 0.15)
				)
				(justify left bottom)
				(hide yes)
			)
		)
		(property "Tolerance" "~"
			(at 322.58 86.36 0)
			(effects
				(font
					(size 1.27 1.27)
				)
				(justify left bottom)
				(hide yes)
			)
		)
		(property "Current" "1A"
			(at 340.36 93.345 0)
			(effects
				(font
					(size 1.27 1.27)
					(thickness 0.15)
				)
				(hide yes)
			)
		)
		(pin "1"
		)
		(pin "2"
		)
		(instances
			(project "k410t-devboard"
				(path ""
					(reference "R349")
					(unit 1)
				)
			)
		)
	)
	(symbol
		(lib_id "antmicropower:GND")
		(at 259.08 69.85 0)
		(mirror y)
		(unit 1)
		(exclude_from_sim no)
		(in_bom yes)
		(on_board yes)
		(dnp no)
		(property "Reference" "#PWR0246"
			(at 259.08 76.2 0)
			(effects
				(font
					(size 1.27 1.27)
				)
				(hide yes)
			)
		)
		(property "Value" "GND"
			(at 257.175 73.66 0)
			(effects
				(font
					(size 1.27 1.27)
				)
				(justify right)
			)
		)
		(property "Footprint" ""
			(at 250.19 77.47 0)
			(effects
				(font
					(size 1.27 1.27)
					(thickness 0.15)
				)
				(justify left bottom)
				(hide yes)
			)
		)
		(property "Datasheet" ""
			(at 250.19 82.55 0)
			(effects
				(font
					(size 1.27 1.27)
					(thickness 0.15)
				)
				(justify left bottom)
				(hide yes)
			)
		)
		(property "Description" ""
			(at 259.08 69.85 0)
			(effects
				(font
					(size 1.27 1.27)
				)
			)
		)
		(property "Author" "Antmicro"
			(at 250.19 77.47 0)
			(effects
				(font
					(size 1.27 1.27)
					(thickness 0.15)
				)
				(justify left bottom)
				(hide yes)
			)
		)
		(property "License" "Apache-2.0"
			(at 250.19 80.01 0)
			(effects
				(font
					(size 1.27 1.27)
					(thickness 0.15)
				)
				(justify left bottom)
				(hide yes)
			)
		)
		(pin "1"
		)
		(instances
			(project "k410t-devboard"
				(path ""
					(reference "#PWR0246")
					(unit 1)
				)
			)
		)
	)
	(symbol
		(lib_id "antmicropower:GND")
		(at 392.43 100.33 0)
		(unit 1)
		(exclude_from_sim no)
		(in_bom yes)
		(on_board yes)
		(dnp no)
		(property "Reference" "#PWR0279"
			(at 392.43 106.68 0)
			(effects
				(font
					(size 1.27 1.27)
				)
				(hide yes)
			)
		)
		(property "Value" "GND"
			(at 392.43 104.14 0)
			(effects
				(font
					(size 1.27 1.27)
				)
			)
		)
		(property "Footprint" ""
			(at 401.32 107.95 0)
			(effects
				(font
					(size 1.27 1.27)
					(thickness 0.15)
				)
				(justify left bottom)
				(hide yes)
			)
		)
		(property "Datasheet" ""
			(at 401.32 113.03 0)
			(effects
				(font
					(size 1.27 1.27)
					(thickness 0.15)
				)
				(justify left bottom)
				(hide yes)
			)
		)
		(property "Description" ""
			(at 392.43 100.33 0)
			(effects
				(font
					(size 1.27 1.27)
				)
			)
		)
		(property "Author" "Antmicro"
			(at 401.32 107.95 0)
			(effects
				(font
					(size 1.27 1.27)
					(thickness 0.15)
				)
				(justify left bottom)
				(hide yes)
			)
		)
		(property "License" "Apache-2.0"
			(at 401.32 110.49 0)
			(effects
				(font
					(size 1.27 1.27)
					(thickness 0.15)
				)
				(justify left bottom)
				(hide yes)
			)
		)
		(pin "1"
		)
		(instances
			(project "k410t-devboard"
				(path ""
					(reference "#PWR0279")
					(unit 1)
				)
			)
		)
	)
	(symbol
		(lib_id "antmicroLogicTranslatorsLevelShifters:TXU0304BQAR")
		(at 313.69 138.43 0)
		(unit 1)
		(exclude_from_sim no)
		(in_bom yes)
		(on_board yes)
		(dnp no)
		(fields_autoplaced yes)
		(property "Reference" "U22"
			(at 322.58 130.81 0)
			(effects
				(font
					(size 1.27 1.27)
				)
			)
		)
		(property "Value" "TXU0304BQAR"
			(at 322.58 134.62 0)
			(effects
				(font
					(size 1.27 1.27)
					(thickness 0.15)
				)
				(hide yes)
			)
		)
		(property "Footprint" "antmicro-footprints:DHVQFN-14-1EP_2.5x3mm"
			(at 345.44 143.51 0)
			(effects
				(font
					(size 1.27 1.27)
					(thickness 0.15)
				)
				(justify left bottom)
				(hide yes)
			)
		)
		(property "Datasheet" "https://www.ti.com/lit/ds/symlink/txu0304.pdf?ts=1637748643258&ref_url=https%253A%252F%252Fwww.ti.com%252Fproduct%252FTXU0304"
			(at 345.44 146.05 0)
			(effects
				(font
					(size 1.27 1.27)
					(thickness 0.15)
				)
				(justify left bottom)
				(hide yes)
			)
		)
		(property "Description" ""
			(at 313.69 138.43 0)
			(effects
				(font
					(size 1.27 1.27)
				)
			)
		)
		(property "MPN" "TXU0304BQAR"
			(at 322.58 133.35 0)
			(effects
				(font
					(size 1.27 1.27)
					(thickness 0.15)
				)
			)
		)
		(property "Manufacturer" "Texas Instruments"
			(at 345.44 151.13 0)
			(effects
				(font
					(size 1.27 1.27)
					(thickness 0.15)
				)
				(justify left bottom)
				(hide yes)
			)
		)
		(property "Author" "Antmicro"
			(at 345.44 153.67 0)
			(effects
				(font
					(size 1.27 1.27)
					(thickness 0.15)
				)
				(justify left bottom)
				(hide yes)
			)
		)
		(property "License" "Apache-2.0"
			(at 345.44 156.21 0)
			(effects
				(font
					(size 1.27 1.27)
					(thickness 0.15)
				)
				(justify left bottom)
				(hide yes)
			)
		)
		(pin "1"
		)
		(pin "10"
		)
		(pin "11"
		)
		(pin "12"
		)
		(pin "13"
		)
		(pin "14"
		)
		(pin "15"
		)
		(pin "2"
		)
		(pin "3"
		)
		(pin "4"
		)
		(pin "5"
		)
		(pin "6"
		)
		(pin "7"
		)
		(pin "8"
		)
		(pin "9"
		)
		(instances
			(project "k410t-devboard"
				(path ""
					(reference "U22")
					(unit 1)
				)
			)
		)
	)
	(symbol
		(lib_id "antmicropower:GND")
		(at 57.15 99.06 0)
		(unit 1)
		(exclude_from_sim no)
		(in_bom yes)
		(on_board yes)
		(dnp no)
		(property "Reference" "#PWR0202"
			(at 57.15 105.41 0)
			(effects
				(font
					(size 1.27 1.27)
				)
				(hide yes)
			)
		)
		(property "Value" "GND"
			(at 57.15 102.87 0)
			(effects
				(font
					(size 1.27 1.27)
				)
			)
		)
		(property "Footprint" ""
			(at 66.04 106.68 0)
			(effects
				(font
					(size 1.27 1.27)
					(thickness 0.15)
				)
				(justify left bottom)
				(hide yes)
			)
		)
		(property "Datasheet" ""
			(at 66.04 111.76 0)
			(effects
				(font
					(size 1.27 1.27)
					(thickness 0.15)
				)
				(justify left bottom)
				(hide yes)
			)
		)
		(property "Description" ""
			(at 57.15 99.06 0)
			(effects
				(font
					(size 1.27 1.27)
				)
			)
		)
		(property "Author" "Antmicro"
			(at 66.04 106.68 0)
			(effects
				(font
					(size 1.27 1.27)
					(thickness 0.15)
				)
				(justify left bottom)
				(hide yes)
			)
		)
		(property "License" "Apache-2.0"
			(at 66.04 109.22 0)
			(effects
				(font
					(size 1.27 1.27)
					(thickness 0.15)
				)
				(justify left bottom)
				(hide yes)
			)
		)
		(pin "1"
		)
		(instances
			(project "k410t-devboard"
				(path ""
					(reference "#PWR0202")
					(unit 1)
				)
			)
		)
	)
	(symbol
		(lib_id "antmicroCapacitors0402:C_100n_0402")
		(at 147.32 151.13 90)
		(unit 1)
		(exclude_from_sim no)
		(in_bom yes)
		(on_board yes)
		(dnp no)
		(property "Reference" "C240"
			(at 147.955 146.685 90)
			(effects
				(font
					(size 1.27 1.27)
				)
				(justify right)
			)
		)
		(property "Value" "C_100n_0402"
			(at 157.48 130.81 0)
			(effects
				(font
					(size 1.27 1.27)
					(thickness 0.15)
				)
				(justify left bottom)
				(hide yes)
			)
		)
		(property "Footprint" "antmicro-footprints:C_0402_1005Metric"
			(at 160.02 130.81 0)
			(effects
				(font
					(size 1.27 1.27)
					(thickness 0.15)
				)
				(justify left bottom)
				(hide yes)
			)
		)
		(property "Datasheet" "https://www.murata.com/products/productdetail?partno=GRM155R61H104KE14%23"
			(at 162.56 130.81 0)
			(effects
				(font
					(size 1.27 1.27)
					(thickness 0.15)
				)
				(justify left bottom)
				(hide yes)
			)
		)
		(property "Description" ""
			(at 147.32 151.13 0)
			(effects
				(font
					(size 1.27 1.27)
				)
			)
		)
		(property "Manufacturer" "Murata"
			(at 167.64 130.81 0)
			(effects
				(font
					(size 1.27 1.27)
					(thickness 0.15)
				)
				(justify left bottom)
				(hide yes)
			)
		)
		(property "MPN" "GRM155R61H104KE14D"
			(at 165.1 130.81 0)
			(effects
				(font
					(size 1.27 1.27)
					(thickness 0.15)
				)
				(justify left bottom)
				(hide yes)
			)
		)
		(property "Val" "100n"
			(at 147.955 150.495 90)
			(effects
				(font
					(size 1.27 1.27)
					(thickness 0.15)
				)
				(justify right)
			)
		)
		(property "License" "Apache-2.0"
			(at 170.18 130.81 0)
			(effects
				(font
					(size 1.27 1.27)
					(thickness 0.15)
				)
				(justify left bottom)
				(hide yes)
			)
		)
		(property "Author" "Antmicro"
			(at 172.72 130.81 0)
			(effects
				(font
					(size 1.27 1.27)
					(thickness 0.15)
				)
				(justify left bottom)
				(hide yes)
			)
		)
		(property "Voltage" "50V"
			(at 175.26 130.81 0)
			(effects
				(font
					(size 1.27 1.27)
				)
				(justify left bottom)
				(hide yes)
			)
		)
		(property "Dielectric" "X5R"
			(at 177.8 130.81 0)
			(effects
				(font
					(size 1.27 1.27)
				)
				(justify left bottom)
				(hide yes)
			)
		)
		(pin "1"
		)
		(pin "2"
		)
		(instances
			(project "k410t-devboard"
				(path ""
					(reference "C240")
					(unit 1)
				)
			)
		)
	)
	(symbol
		(lib_id "antmicropower:+3.3V")
		(at 110.49 52.07 0)
		(unit 1)
		(exclude_from_sim no)
		(in_bom yes)
		(on_board yes)
		(dnp no)
		(property "Reference" "#PWR0194"
			(at 110.49 55.88 0)
			(effects
				(font
					(size 1.27 1.27)
				)
				(hide yes)
			)
		)
		(property "Value" "+3V3"
			(at 110.49 48.26 0)
			(effects
				(font
					(size 1.27 1.27)
				)
			)
		)
		(property "Footprint" ""
			(at 110.49 52.07 0)
			(effects
				(font
					(size 1.27 1.27)
				)
				(hide yes)
			)
		)
		(property "Datasheet" ""
			(at 110.49 52.07 0)
			(effects
				(font
					(size 1.27 1.27)
				)
				(hide yes)
			)
		)
		(property "Description" ""
			(at 110.49 52.07 0)
			(effects
				(font
					(size 1.27 1.27)
				)
			)
		)
		(pin "1"
		)
		(instances
			(project "k410t-devboard"
				(path ""
					(reference "#PWR0194")
					(unit 1)
				)
			)
		)
	)
	(symbol
		(lib_id "antmicropower:GND")
		(at 237.49 81.28 0)
		(mirror y)
		(unit 1)
		(exclude_from_sim no)
		(in_bom yes)
		(on_board yes)
		(dnp no)
		(property "Reference" "#PWR0244"
			(at 237.49 87.63 0)
			(effects
				(font
					(size 1.27 1.27)
				)
				(hide yes)
			)
		)
		(property "Value" "GND"
			(at 237.49 85.09 0)
			(effects
				(font
					(size 1.27 1.27)
				)
			)
		)
		(property "Footprint" ""
			(at 228.6 88.9 0)
			(effects
				(font
					(size 1.27 1.27)
					(thickness 0.15)
				)
				(justify left bottom)
				(hide yes)
			)
		)
		(property "Datasheet" ""
			(at 228.6 93.98 0)
			(effects
				(font
					(size 1.27 1.27)
					(thickness 0.15)
				)
				(justify left bottom)
				(hide yes)
			)
		)
		(property "Description" ""
			(at 237.49 81.28 0)
			(effects
				(font
					(size 1.27 1.27)
				)
			)
		)
		(property "Author" "Antmicro"
			(at 228.6 88.9 0)
			(effects
				(font
					(size 1.27 1.27)
					(thickness 0.15)
				)
				(justify left bottom)
				(hide yes)
			)
		)
		(property "License" "Apache-2.0"
			(at 228.6 91.44 0)
			(effects
				(font
					(size 1.27 1.27)
					(thickness 0.15)
				)
				(justify left bottom)
				(hide yes)
			)
		)
		(pin "1"
		)
		(instances
			(project "k410t-devboard"
				(path ""
					(reference "#PWR0244")
					(unit 1)
				)
			)
		)
	)
	(symbol
		(lib_id "antmicropower:GND")
		(at 353.06 83.82 0)
		(unit 1)
		(exclude_from_sim no)
		(in_bom yes)
		(on_board yes)
		(dnp no)
		(property "Reference" "#PWR0270"
			(at 353.06 90.17 0)
			(effects
				(font
					(size 1.27 1.27)
				)
				(hide yes)
			)
		)
		(property "Value" "GND"
			(at 354.965 87.63 0)
			(effects
				(font
					(size 1.27 1.27)
				)
				(justify right)
			)
		)
		(property "Footprint" ""
			(at 361.95 91.44 0)
			(effects
				(font
					(size 1.27 1.27)
					(thickness 0.15)
				)
				(justify left bottom)
				(hide yes)
			)
		)
		(property "Datasheet" ""
			(at 361.95 96.52 0)
			(effects
				(font
					(size 1.27 1.27)
					(thickness 0.15)
				)
				(justify left bottom)
				(hide yes)
			)
		)
		(property "Description" ""
			(at 353.06 83.82 0)
			(effects
				(font
					(size 1.27 1.27)
				)
			)
		)
		(property "Author" "Antmicro"
			(at 361.95 91.44 0)
			(effects
				(font
					(size 1.27 1.27)
					(thickness 0.15)
				)
				(justify left bottom)
				(hide yes)
			)
		)
		(property "License" "Apache-2.0"
			(at 361.95 93.98 0)
			(effects
				(font
					(size 1.27 1.27)
					(thickness 0.15)
				)
				(justify left bottom)
				(hide yes)
			)
		)
		(pin "1"
		)
		(instances
			(project "k410t-devboard"
				(path ""
					(reference "#PWR0270")
					(unit 1)
				)
			)
		)
	)
	(symbol
		(lib_id "antmicropower:GND")
		(at 77.47 97.79 0)
		(unit 1)
		(exclude_from_sim no)
		(in_bom yes)
		(on_board yes)
		(dnp no)
		(property "Reference" "#PWR0208"
			(at 77.47 104.14 0)
			(effects
				(font
					(size 1.27 1.27)
				)
				(hide yes)
			)
		)
		(property "Value" "GND"
			(at 77.47 101.6 0)
			(effects
				(font
					(size 1.27 1.27)
				)
			)
		)
		(property "Footprint" ""
			(at 86.36 105.41 0)
			(effects
				(font
					(size 1.27 1.27)
					(thickness 0.15)
				)
				(justify left bottom)
				(hide yes)
			)
		)
		(property "Datasheet" ""
			(at 86.36 110.49 0)
			(effects
				(font
					(size 1.27 1.27)
					(thickness 0.15)
				)
				(justify left bottom)
				(hide yes)
			)
		)
		(property "Description" ""
			(at 77.47 97.79 0)
			(effects
				(font
					(size 1.27 1.27)
				)
			)
		)
		(property "Author" "Antmicro"
			(at 86.36 105.41 0)
			(effects
				(font
					(size 1.27 1.27)
					(thickness 0.15)
				)
				(justify left bottom)
				(hide yes)
			)
		)
		(property "License" "Apache-2.0"
			(at 86.36 107.95 0)
			(effects
				(font
					(size 1.27 1.27)
					(thickness 0.15)
				)
				(justify left bottom)
				(hide yes)
			)
		)
		(pin "1"
		)
		(instances
			(project "k410t-devboard"
				(path ""
					(reference "#PWR0208")
					(unit 1)
				)
			)
		)
	)
	(symbol
		(lib_id "antmicroCapacitors0402:C_100n_0402")
		(at 375.92 245.11 90)
		(unit 1)
		(exclude_from_sim no)
		(in_bom yes)
		(on_board yes)
		(dnp no)
		(property "Reference" "C250"
			(at 376.555 240.665 90)
			(effects
				(font
					(size 1.27 1.27)
				)
				(justify right)
			)
		)
		(property "Value" "C_100n_0402"
			(at 386.08 224.79 0)
			(effects
				(font
					(size 1.27 1.27)
					(thickness 0.15)
				)
				(justify left bottom)
				(hide yes)
			)
		)
		(property "Footprint" "antmicro-footprints:C_0402_1005Metric"
			(at 388.62 224.79 0)
			(effects
				(font
					(size 1.27 1.27)
					(thickness 0.15)
				)
				(justify left bottom)
				(hide yes)
			)
		)
		(property "Datasheet" "https://www.murata.com/products/productdetail?partno=GRM155R61H104KE14%23"
			(at 391.16 224.79 0)
			(effects
				(font
					(size 1.27 1.27)
					(thickness 0.15)
				)
				(justify left bottom)
				(hide yes)
			)
		)
		(property "Description" ""
			(at 375.92 245.11 0)
			(effects
				(font
					(size 1.27 1.27)
				)
			)
		)
		(property "Manufacturer" "Murata"
			(at 396.24 224.79 0)
			(effects
				(font
					(size 1.27 1.27)
					(thickness 0.15)
				)
				(justify left bottom)
				(hide yes)
			)
		)
		(property "MPN" "GRM155R61H104KE14D"
			(at 393.7 224.79 0)
			(effects
				(font
					(size 1.27 1.27)
					(thickness 0.15)
				)
				(justify left bottom)
				(hide yes)
			)
		)
		(property "Val" "100n"
			(at 376.555 244.475 90)
			(effects
				(font
					(size 1.27 1.27)
					(thickness 0.15)
				)
				(justify right)
			)
		)
		(property "License" "Apache-2.0"
			(at 398.78 224.79 0)
			(effects
				(font
					(size 1.27 1.27)
					(thickness 0.15)
				)
				(justify left bottom)
				(hide yes)
			)
		)
		(property "Author" "Antmicro"
			(at 401.32 224.79 0)
			(effects
				(font
					(size 1.27 1.27)
					(thickness 0.15)
				)
				(justify left bottom)
				(hide yes)
			)
		)
		(property "Voltage" "50V"
			(at 403.86 224.79 0)
			(effects
				(font
					(size 1.27 1.27)
				)
				(justify left bottom)
				(hide yes)
			)
		)
		(property "Dielectric" "X5R"
			(at 406.4 224.79 0)
			(effects
				(font
					(size 1.27 1.27)
				)
				(justify left bottom)
				(hide yes)
			)
		)
		(pin "1"
		)
		(pin "2"
		)
		(instances
			(project "k410t-devboard"
				(path ""
					(reference "C250")
					(unit 1)
				)
			)
		)
	)
	(symbol
		(lib_id "antmicroLEDIndicationDiscrete:LED_G_0603_KP-1608CGCK")
		(at 53.34 238.76 0)
		(unit 1)
		(exclude_from_sim no)
		(in_bom yes)
		(on_board yes)
		(dnp no)
		(property "Reference" "D26"
			(at 64.135 236.855 0)
			(effects
				(font
					(size 1.27 1.27)
				)
				(justify right)
			)
		)
		(property "Value" "LED_G_0603_KP-1608CGCK"
			(at 60.96 238.125 0)
			(effects
				(font
					(size 1.27 1.27)
					(thickness 0.15)
				)
				(justify left bottom)
				(hide yes)
			)
		)
		(property "Footprint" "antmicro-footprints:LED_0603_1608Metric_G"
			(at 76.2 248.92 0)
			(effects
				(font
					(size 1.27 1.27)
					(thickness 0.15)
				)
				(justify left bottom)
				(hide yes)
			)
		)
		(property "Datasheet" "http://www.kingbright.com/attachments/file/psearch//000/00/00/KP-1608CGCK(Ver.23B).pdf"
			(at 76.2 251.46 0)
			(effects
				(font
					(size 1.27 1.27)
					(thickness 0.15)
				)
				(justify left bottom)
				(hide yes)
			)
		)
		(property "Description" ""
			(at 53.34 238.76 0)
			(effects
				(font
					(size 1.27 1.27)
				)
			)
		)
		(property "MPN" "KP-1608CGCK"
			(at 76.2 254 0)
			(effects
				(font
					(size 1.27 1.27)
					(thickness 0.15)
				)
				(justify left bottom)
				(hide yes)
			)
		)
		(property "Manufacturer" "Kingbright"
			(at 76.2 256.54 0)
			(effects
				(font
					(size 1.27 1.27)
					(thickness 0.15)
				)
				(justify left bottom)
				(hide yes)
			)
		)
		(property "Author" "Antmicro"
			(at 76.2 259.08 0)
			(effects
				(font
					(size 1.27 1.27)
					(thickness 0.15)
				)
				(justify left bottom)
				(hide yes)
			)
		)
		(property "License" "Apache-2.0"
			(at 76.2 261.62 0)
			(effects
				(font
					(size 1.27 1.27)
					(thickness 0.15)
				)
				(justify left bottom)
				(hide yes)
			)
		)
		(property "Color" "Green"
			(at 48.26 237.49 0)
			(effects
				(font
					(size 1.27 1.27)
				)
				(justify left bottom)
			)
		)
		(pin "1"
		)
		(pin "2"
		)
		(instances
			(project "k410t-devboard"
				(path ""
					(reference "D26")
					(unit 1)
				)
			)
		)
	)
	(symbol
		(lib_id "antmicropower:GND")
		(at 307.34 34.29 0)
		(unit 1)
		(exclude_from_sim no)
		(in_bom yes)
		(on_board yes)
		(dnp no)
		(property "Reference" "#PWR0260"
			(at 307.34 40.64 0)
			(effects
				(font
					(size 1.27 1.27)
				)
				(hide yes)
			)
		)
		(property "Value" "GND"
			(at 307.34 38.1 0)
			(effects
				(font
					(size 1.27 1.27)
				)
			)
		)
		(property "Footprint" ""
			(at 316.23 41.91 0)
			(effects
				(font
					(size 1.27 1.27)
					(thickness 0.15)
				)
				(justify left bottom)
				(hide yes)
			)
		)
		(property "Datasheet" ""
			(at 316.23 46.99 0)
			(effects
				(font
					(size 1.27 1.27)
					(thickness 0.15)
				)
				(justify left bottom)
				(hide yes)
			)
		)
		(property "Description" ""
			(at 307.34 34.29 0)
			(effects
				(font
					(size 1.27 1.27)
				)
			)
		)
		(property "Author" "Antmicro"
			(at 316.23 41.91 0)
			(effects
				(font
					(size 1.27 1.27)
					(thickness 0.15)
				)
				(justify left bottom)
				(hide yes)
			)
		)
		(property "License" "Apache-2.0"
			(at 316.23 44.45 0)
			(effects
				(font
					(size 1.27 1.27)
					(thickness 0.15)
				)
				(justify left bottom)
				(hide yes)
			)
		)
		(pin "1"
		)
		(instances
			(project "k410t-devboard"
				(path ""
					(reference "#PWR0260")
					(unit 1)
				)
			)
		)
	)
	(symbol
		(lib_id "antmicropower:GND")
		(at 59.69 143.51 0)
		(mirror y)
		(unit 1)
		(exclude_from_sim no)
		(in_bom yes)
		(on_board yes)
		(dnp no)
		(property "Reference" "#PWR0204"
			(at 59.69 149.86 0)
			(effects
				(font
					(size 1.27 1.27)
				)
				(hide yes)
			)
		)
		(property "Value" "GND"
			(at 59.69 147.32 0)
			(effects
				(font
					(size 1.27 1.27)
				)
			)
		)
		(property "Footprint" ""
			(at 50.8 151.13 0)
			(effects
				(font
					(size 1.27 1.27)
					(thickness 0.15)
				)
				(justify left bottom)
				(hide yes)
			)
		)
		(property "Datasheet" ""
			(at 50.8 156.21 0)
			(effects
				(font
					(size 1.27 1.27)
					(thickness 0.15)
				)
				(justify left bottom)
				(hide yes)
			)
		)
		(property "Description" ""
			(at 59.69 143.51 0)
			(effects
				(font
					(size 1.27 1.27)
				)
			)
		)
		(property "Author" "Antmicro"
			(at 50.8 151.13 0)
			(effects
				(font
					(size 1.27 1.27)
					(thickness 0.15)
				)
				(justify left bottom)
				(hide yes)
			)
		)
		(property "License" "Apache-2.0"
			(at 50.8 153.67 0)
			(effects
				(font
					(size 1.27 1.27)
					(thickness 0.15)
				)
				(justify left bottom)
				(hide yes)
			)
		)
		(pin "1"
		)
		(instances
			(project "k410t-devboard"
				(path ""
					(reference "#PWR0204")
					(unit 1)
				)
			)
		)
	)
	(symbol
		(lib_id "antmicroCapacitors0402:C_100n_0402")
		(at 353.06 81.28 90)
		(unit 1)
		(exclude_from_sim no)
		(in_bom yes)
		(on_board yes)
		(dnp no)
		(property "Reference" "C395"
			(at 353.695 76.835 90)
			(effects
				(font
					(size 1.27 1.27)
				)
				(justify right)
			)
		)
		(property "Value" "C_100n_0402"
			(at 363.22 60.96 0)
			(effects
				(font
					(size 1.27 1.27)
					(thickness 0.15)
				)
				(justify left bottom)
				(hide yes)
			)
		)
		(property "Footprint" "antmicro-footprints:C_0402_1005Metric"
			(at 365.76 60.96 0)
			(effects
				(font
					(size 1.27 1.27)
					(thickness 0.15)
				)
				(justify left bottom)
				(hide yes)
			)
		)
		(property "Datasheet" "https://www.murata.com/products/productdetail?partno=GRM155R61H104KE14%23"
			(at 368.3 60.96 0)
			(effects
				(font
					(size 1.27 1.27)
					(thickness 0.15)
				)
				(justify left bottom)
				(hide yes)
			)
		)
		(property "Description" ""
			(at 353.06 81.28 0)
			(effects
				(font
					(size 1.27 1.27)
				)
			)
		)
		(property "Manufacturer" "Murata"
			(at 373.38 60.96 0)
			(effects
				(font
					(size 1.27 1.27)
					(thickness 0.15)
				)
				(justify left bottom)
				(hide yes)
			)
		)
		(property "MPN" "GRM155R61H104KE14D"
			(at 370.84 60.96 0)
			(effects
				(font
					(size 1.27 1.27)
					(thickness 0.15)
				)
				(justify left bottom)
				(hide yes)
			)
		)
		(property "Val" "100n"
			(at 353.695 80.645 90)
			(effects
				(font
					(size 1.27 1.27)
					(thickness 0.15)
				)
				(justify right)
			)
		)
		(property "License" "Apache-2.0"
			(at 375.92 60.96 0)
			(effects
				(font
					(size 1.27 1.27)
					(thickness 0.15)
				)
				(justify left bottom)
				(hide yes)
			)
		)
		(property "Author" "Antmicro"
			(at 378.46 60.96 0)
			(effects
				(font
					(size 1.27 1.27)
					(thickness 0.15)
				)
				(justify left bottom)
				(hide yes)
			)
		)
		(property "Voltage" "50V"
			(at 381 60.96 0)
			(effects
				(font
					(size 1.27 1.27)
				)
				(justify left bottom)
				(hide yes)
			)
		)
		(property "Dielectric" "X5R"
			(at 383.54 60.96 0)
			(effects
				(font
					(size 1.27 1.27)
				)
				(justify left bottom)
				(hide yes)
			)
		)
		(pin "1"
		)
		(pin "2"
		)
		(instances
			(project "k410t-devboard"
				(path ""
					(reference "C395")
					(unit 1)
				)
			)
		)
	)
	(symbol
		(lib_id "antmicropower:+3.3V")
		(at 334.01 168.91 0)
		(unit 1)
		(exclude_from_sim no)
		(in_bom yes)
		(on_board yes)
		(dnp no)
		(property "Reference" "#PWR0236"
			(at 334.01 172.72 0)
			(effects
				(font
					(size 1.27 1.27)
				)
				(hide yes)
			)
		)
		(property "Value" "+3V3"
			(at 334.01 165.354 0)
			(effects
				(font
					(size 1.27 1.27)
				)
			)
		)
		(property "Footprint" ""
			(at 334.01 168.91 0)
			(effects
				(font
					(size 1.27 1.27)
				)
				(hide yes)
			)
		)
		(property "Datasheet" ""
			(at 334.01 168.91 0)
			(effects
				(font
					(size 1.27 1.27)
				)
				(hide yes)
			)
		)
		(property "Description" ""
			(at 334.01 168.91 0)
			(effects
				(font
					(size 1.27 1.27)
				)
			)
		)
		(pin "1"
		)
		(instances
			(project "k410t-devboard"
				(path ""
					(reference "#PWR0236")
					(unit 1)
				)
			)
		)
	)
	(symbol
		(lib_id "antmicropower:GND")
		(at 34.29 260.35 0)
		(unit 1)
		(exclude_from_sim no)
		(in_bom yes)
		(on_board yes)
		(dnp no)
		(property "Reference" "#PWR0198"
			(at 34.29 266.7 0)
			(effects
				(font
					(size 1.27 1.27)
				)
				(hide yes)
			)
		)
		(property "Value" "GND"
			(at 34.29 264.16 0)
			(effects
				(font
					(size 1.27 1.27)
				)
			)
		)
		(property "Footprint" ""
			(at 43.18 267.97 0)
			(effects
				(font
					(size 1.27 1.27)
					(thickness 0.15)
				)
				(justify left bottom)
				(hide yes)
			)
		)
		(property "Datasheet" ""
			(at 43.18 273.05 0)
			(effects
				(font
					(size 1.27 1.27)
					(thickness 0.15)
				)
				(justify left bottom)
				(hide yes)
			)
		)
		(property "Description" ""
			(at 34.29 260.35 0)
			(effects
				(font
					(size 1.27 1.27)
				)
			)
		)
		(property "Author" "Antmicro"
			(at 43.18 267.97 0)
			(effects
				(font
					(size 1.27 1.27)
					(thickness 0.15)
				)
				(justify left bottom)
				(hide yes)
			)
		)
		(property "License" "Apache-2.0"
			(at 43.18 270.51 0)
			(effects
				(font
					(size 1.27 1.27)
					(thickness 0.15)
				)
				(justify left bottom)
				(hide yes)
			)
		)
		(pin "1"
		)
		(instances
			(project "k410t-devboard"
				(path ""
					(reference "#PWR0198")
					(unit 1)
				)
			)
		)
	)
	(symbol
		(lib_id "antmicroResistors0402:R_0R_0402")
		(at 350.52 208.28 180)
		(unit 1)
		(exclude_from_sim no)
		(in_bom no)
		(on_board yes)
		(dnp yes)
		(property "Reference" "R187"
			(at 353.06 207.01 0)
			(effects
				(font
					(size 1.27 1.27)
				)
			)
		)
		(property "Value" "R_0R_0402"
			(at 330.2 195.58 0)
			(effects
				(font
					(size 1.27 1.27)
					(thickness 0.15)
				)
				(justify left bottom)
				(hide yes)
			)
		)
		(property "Footprint" "antmicro-footprints:R_0402_1005Metric"
			(at 330.2 193.04 0)
			(effects
				(font
					(size 1.27 1.27)
					(thickness 0.15)
				)
				(justify left bottom)
				(hide yes)
			)
		)
		(property "Datasheet" "https://industrial.panasonic.com/cdbs/www-data/pdf/RDA0000/AOA0000C301.pdf"
			(at 330.2 190.5 0)
			(effects
				(font
					(size 1.27 1.27)
					(thickness 0.15)
				)
				(justify left bottom)
				(hide yes)
			)
		)
		(property "Description" ""
			(at 350.52 208.28 0)
			(effects
				(font
					(size 1.27 1.27)
				)
			)
		)
		(property "Manufacturer" "Panasonic"
			(at 330.2 185.42 0)
			(effects
				(font
					(size 1.27 1.27)
					(thickness 0.15)
				)
				(justify left bottom)
				(hide yes)
			)
		)
		(property "MPN" "ERJ2GE0R00X"
			(at 330.2 187.96 0)
			(effects
				(font
					(size 1.27 1.27)
					(thickness 0.15)
				)
				(justify left bottom)
				(hide yes)
			)
		)
		(property "Val" "0R"
			(at 344.17 207.01 0)
			(effects
				(font
					(size 1.27 1.27)
					(thickness 0.15)
				)
			)
		)
		(property "DNP" "DNP"
			(at 347.98 208.28 0)
			(effects
				(font
					(size 1.27 1.27)
				)
			)
		)
		(property "License" "Apache-2.0"
			(at 330.2 182.88 0)
			(effects
				(font
					(size 1.27 1.27)
					(thickness 0.15)
				)
				(justify left bottom)
				(hide yes)
			)
		)
		(property "Author" "Antmicro"
			(at 330.2 180.34 0)
			(effects
				(font
					(size 1.27 1.27)
					(thickness 0.15)
				)
				(justify left bottom)
				(hide yes)
			)
		)
		(property "Tolerance" "~"
			(at 330.2 198.12 0)
			(effects
				(font
					(size 1.27 1.27)
				)
				(justify left bottom)
				(hide yes)
			)
		)
		(property "Current" "1A"
			(at 347.98 220.345 0)
			(effects
				(font
					(size 1.27 1.27)
					(thickness 0.15)
				)
				(hide yes)
			)
		)
		(pin "1"
		)
		(pin "2"
		)
		(instances
			(project "k410t-devboard"
				(path ""
					(reference "R187")
					(unit 1)
				)
			)
		)
	)
	(symbol
		(lib_id "antmicroResistors0402:R_33R_0402")
		(at 238.76 208.28 0)
		(unit 1)
		(exclude_from_sim no)
		(in_bom yes)
		(on_board yes)
		(dnp no)
		(property "Reference" "R163"
			(at 243.84 207.01 0)
			(effects
				(font
					(size 1.27 1.27)
				)
				(justify left)
			)
		)
		(property "Value" "R_33R_0402"
			(at 259.08 220.98 0)
			(effects
				(font
					(size 1.27 1.27)
					(thickness 0.15)
				)
				(justify left bottom)
				(hide yes)
			)
		)
		(property "Footprint" "antmicro-footprints:R_0402_1005Metric"
			(at 259.08 223.52 0)
			(effects
				(font
					(size 1.27 1.27)
					(thickness 0.15)
				)
				(justify left bottom)
				(hide yes)
			)
		)
		(property "Datasheet" "https://www.bourns.com/docs/product-datasheets/cr.pdf"
			(at 259.08 226.06 0)
			(effects
				(font
					(size 1.27 1.27)
					(thickness 0.15)
				)
				(justify left bottom)
				(hide yes)
			)
		)
		(property "Description" ""
			(at 238.76 208.28 0)
			(effects
				(font
					(size 1.27 1.27)
				)
			)
		)
		(property "Manufacturer" "Bourns"
			(at 259.08 231.14 0)
			(effects
				(font
					(size 1.27 1.27)
					(thickness 0.15)
				)
				(justify left bottom)
				(hide yes)
			)
		)
		(property "MPN" "CR0402-FX-33R0GLF"
			(at 259.08 228.6 0)
			(effects
				(font
					(size 1.27 1.27)
					(thickness 0.15)
				)
				(justify left bottom)
				(hide yes)
			)
		)
		(property "Val" "33R"
			(at 234.95 208.28 0)
			(effects
				(font
					(size 1.27 1.27)
					(thickness 0.15)
				)
				(justify left bottom)
			)
		)
		(property "License" "Apache-2.0"
			(at 259.08 233.68 0)
			(effects
				(font
					(size 1.27 1.27)
					(thickness 0.15)
				)
				(justify left bottom)
				(hide yes)
			)
		)
		(property "Author" "Antmicro"
			(at 259.08 236.22 0)
			(effects
				(font
					(size 1.27 1.27)
					(thickness 0.15)
				)
				(justify left bottom)
				(hide yes)
			)
		)
		(property "Tolerance" "1%"
			(at 259.08 218.44 0)
			(effects
				(font
					(size 1.27 1.27)
				)
				(justify left bottom)
				(hide yes)
			)
		)
		(pin "1"
		)
		(pin "2"
		)
		(instances
			(project "k410t-devboard"
				(path ""
					(reference "R163")
					(unit 1)
				)
			)
		)
	)
	(symbol
		(lib_id "antmicropower:GND")
		(at 30.48 143.51 0)
		(mirror y)
		(unit 1)
		(exclude_from_sim no)
		(in_bom yes)
		(on_board yes)
		(dnp no)
		(fields_autoplaced yes)
		(property "Reference" "#PWR0197"
			(at 30.48 149.86 0)
			(effects
				(font
					(size 1.27 1.27)
				)
				(hide yes)
			)
		)
		(property "Value" "GND"
			(at 30.48 148.59 0)
			(effects
				(font
					(size 1.27 1.27)
				)
			)
		)
		(property "Footprint" ""
			(at 21.59 151.13 0)
			(effects
				(font
					(size 1.27 1.27)
					(thickness 0.15)
				)
				(justify left bottom)
				(hide yes)
			)
		)
		(property "Datasheet" ""
			(at 21.59 156.21 0)
			(effects
				(font
					(size 1.27 1.27)
					(thickness 0.15)
				)
				(justify left bottom)
				(hide yes)
			)
		)
		(property "Description" ""
			(at 30.48 143.51 0)
			(effects
				(font
					(size 1.27 1.27)
				)
			)
		)
		(property "Author" "Antmicro"
			(at 21.59 151.13 0)
			(effects
				(font
					(size 1.27 1.27)
					(thickness 0.15)
				)
				(justify left bottom)
				(hide yes)
			)
		)
		(property "License" "Apache-2.0"
			(at 21.59 153.67 0)
			(effects
				(font
					(size 1.27 1.27)
					(thickness 0.15)
				)
				(justify left bottom)
				(hide yes)
			)
		)
		(pin "1"
		)
		(instances
			(project "k410t-devboard"
				(path ""
					(reference "#PWR0197")
					(unit 1)
				)
			)
		)
	)
	(symbol
		(lib_id "antmicroResistors0402:R_0R_0402")
		(at 234.95 245.11 0)
		(mirror y)
		(unit 1)
		(exclude_from_sim no)
		(in_bom yes)
		(on_board yes)
		(dnp no)
		(property "Reference" "R165"
			(at 232.41 240.03 0)
			(effects
				(font
					(size 1.27 1.27)
				)
			)
		)
		(property "Value" "R_0R_0402"
			(at 214.63 257.81 0)
			(effects
				(font
					(size 1.27 1.27)
					(thickness 0.15)
				)
				(justify left bottom)
				(hide yes)
			)
		)
		(property "Footprint" "antmicro-footprints:R_0402_1005Metric"
			(at 214.63 260.35 0)
			(effects
				(font
					(size 1.27 1.27)
					(thickness 0.15)
				)
				(justify left bottom)
				(hide yes)
			)
		)
		(property "Datasheet" "https://industrial.panasonic.com/cdbs/www-data/pdf/RDA0000/AOA0000C301.pdf"
			(at 214.63 262.89 0)
			(effects
				(font
					(size 1.27 1.27)
					(thickness 0.15)
				)
				(justify left bottom)
				(hide yes)
			)
		)
		(property "Description" ""
			(at 234.95 245.11 0)
			(effects
				(font
					(size 1.27 1.27)
				)
			)
		)
		(property "Manufacturer" "Panasonic"
			(at 214.63 267.97 0)
			(effects
				(font
					(size 1.27 1.27)
					(thickness 0.15)
				)
				(justify left bottom)
				(hide yes)
			)
		)
		(property "MPN" "ERJ2GE0R00X"
			(at 214.63 265.43 0)
			(effects
				(font
					(size 1.27 1.27)
					(thickness 0.15)
				)
				(justify left bottom)
				(hide yes)
			)
		)
		(property "Val" "0R"
			(at 232.41 242.57 0)
			(effects
				(font
					(size 1.27 1.27)
					(thickness 0.15)
				)
			)
		)
		(property "License" "Apache-2.0"
			(at 214.63 270.51 0)
			(effects
				(font
					(size 1.27 1.27)
					(thickness 0.15)
				)
				(justify left bottom)
				(hide yes)
			)
		)
		(property "Author" "Antmicro"
			(at 214.63 273.05 0)
			(effects
				(font
					(size 1.27 1.27)
					(thickness 0.15)
				)
				(justify left bottom)
				(hide yes)
			)
		)
		(property "Tolerance" "~"
			(at 214.63 255.27 0)
			(effects
				(font
					(size 1.27 1.27)
				)
				(justify left bottom)
				(hide yes)
			)
		)
		(property "Current" "1A"
			(at 232.41 241.935 0)
			(effects
				(font
					(size 1.27 1.27)
					(thickness 0.15)
				)
				(hide yes)
			)
		)
		(pin "1"
		)
		(pin "2"
		)
		(instances
			(project "k410t-devboard"
				(path ""
					(reference "R165")
					(unit 1)
				)
			)
		)
	)
	(symbol
		(lib_id "antmicroTVSDiodes:TPD4E05U06QDQARQ1")
		(at 66.04 199.39 90)
		(mirror x)
		(unit 1)
		(exclude_from_sim no)
		(in_bom yes)
		(on_board yes)
		(dnp no)
		(fields_autoplaced yes)
		(property "Reference" "U17"
			(at 70.485 210.82 90)
			(effects
				(font
					(size 1.27 1.27)
				)
			)
		)
		(property "Value" "TPD4E05U06QDQARQ1"
			(at 63.5 212.725 90)
			(effects
				(font
					(size 1.27 1.27)
					(thickness 0.15)
				)
				(justify right)
				(hide yes)
			)
		)
		(property "Footprint" "antmicro-footprints:USON-10_2.5x1mm_P0.5mm"
			(at 71.12 223.52 0)
			(effects
				(font
					(size 1.27 1.27)
					(thickness 0.15)
				)
				(justify left bottom)
				(hide yes)
			)
		)
		(property "Datasheet" "https://www.ti.com/lit/ds/symlink/tpd4e05u06-q1.pdf?HQS=dis-mous-null-mousermode-dsf-pf-null-wwe&ts=1663591265741&ref_url=https%253A%252F%252Fwww.mouser.com%252F"
			(at 73.66 223.52 0)
			(effects
				(font
					(size 1.27 1.27)
					(thickness 0.15)
				)
				(justify left bottom)
				(hide yes)
			)
		)
		(property "Description" ""
			(at 66.04 199.39 0)
			(effects
				(font
					(size 1.27 1.27)
				)
			)
		)
		(property "Manufacturer" "Texas Instruments"
			(at 76.2 223.52 0)
			(effects
				(font
					(size 1.27 1.27)
					(thickness 0.15)
				)
				(justify left bottom)
				(hide yes)
			)
		)
		(property "MPN" "TPD4E05U06QDQARQ1"
			(at 70.485 213.36 90)
			(effects
				(font
					(size 1.27 1.27)
					(thickness 0.15)
				)
			)
		)
		(property "Author" "Antmicro"
			(at 81.28 223.52 0)
			(effects
				(font
					(size 1.27 1.27)
					(thickness 0.15)
				)
				(justify left bottom)
				(hide yes)
			)
		)
		(property "License" "Apache-2.0"
			(at 83.82 223.52 0)
			(effects
				(font
					(size 1.27 1.27)
					(thickness 0.15)
				)
				(justify left bottom)
				(hide yes)
			)
		)
		(pin "1"
		)
		(pin "10"
		)
		(pin "2"
		)
		(pin "3"
		)
		(pin "4"
		)
		(pin "5"
		)
		(pin "6"
		)
		(pin "7"
		)
		(pin "8"
		)
		(pin "9"
		)
		(instances
			(project "k410t-devboard"
				(path ""
					(reference "U17")
					(unit 1)
				)
			)
		)
	)
	(symbol
		(lib_id "antmicroResistors0402:R_33R_0402")
		(at 106.68 39.37 0)
		(unit 1)
		(exclude_from_sim no)
		(in_bom yes)
		(on_board yes)
		(dnp no)
		(property "Reference" "R154"
			(at 114.3 38.1 0)
			(effects
				(font
					(size 1.27 1.27)
				)
			)
		)
		(property "Value" "R_33R_0402"
			(at 127 52.07 0)
			(effects
				(font
					(size 1.27 1.27)
					(thickness 0.15)
				)
				(justify left bottom)
				(hide yes)
			)
		)
		(property "Footprint" "antmicro-footprints:R_0402_1005Metric"
			(at 127 54.61 0)
			(effects
				(font
					(size 1.27 1.27)
					(thickness 0.15)
				)
				(justify left bottom)
				(hide yes)
			)
		)
		(property "Datasheet" "https://www.bourns.com/docs/product-datasheets/cr.pdf"
			(at 127 57.15 0)
			(effects
				(font
					(size 1.27 1.27)
					(thickness 0.15)
				)
				(justify left bottom)
				(hide yes)
			)
		)
		(property "Description" ""
			(at 106.68 39.37 0)
			(effects
				(font
					(size 1.27 1.27)
				)
			)
		)
		(property "Manufacturer" "Bourns"
			(at 127 62.23 0)
			(effects
				(font
					(size 1.27 1.27)
					(thickness 0.15)
				)
				(justify left bottom)
				(hide yes)
			)
		)
		(property "MPN" "CR0402-FX-33R0GLF"
			(at 127 59.69 0)
			(effects
				(font
					(size 1.27 1.27)
					(thickness 0.15)
				)
				(justify left bottom)
				(hide yes)
			)
		)
		(property "Val" "33R"
			(at 104.775 38.1 0)
			(effects
				(font
					(size 1.27 1.27)
					(thickness 0.15)
				)
			)
		)
		(property "License" "Apache-2.0"
			(at 127 64.77 0)
			(effects
				(font
					(size 1.27 1.27)
					(thickness 0.15)
				)
				(justify left bottom)
				(hide yes)
			)
		)
		(property "Author" "Antmicro"
			(at 127 67.31 0)
			(effects
				(font
					(size 1.27 1.27)
					(thickness 0.15)
				)
				(justify left bottom)
				(hide yes)
			)
		)
		(property "Tolerance" "1%"
			(at 127 49.53 0)
			(effects
				(font
					(size 1.27 1.27)
				)
				(justify left bottom)
				(hide yes)
			)
		)
		(pin "1"
		)
		(pin "2"
		)
		(instances
			(project "k410t-devboard"
				(path ""
					(reference "R154")
					(unit 1)
				)
			)
		)
	)
	(symbol
		(lib_id "antmicropower:GND")
		(at 81.28 203.2 0)
		(mirror y)
		(unit 1)
		(exclude_from_sim no)
		(in_bom yes)
		(on_board yes)
		(dnp no)
		(property "Reference" "#PWR0209"
			(at 81.28 209.55 0)
			(effects
				(font
					(size 1.27 1.27)
				)
				(hide yes)
			)
		)
		(property "Value" "GND"
			(at 81.28 207.01 0)
			(effects
				(font
					(size 1.27 1.27)
				)
			)
		)
		(property "Footprint" ""
			(at 72.39 210.82 0)
			(effects
				(font
					(size 1.27 1.27)
					(thickness 0.15)
				)
				(justify left bottom)
				(hide yes)
			)
		)
		(property "Datasheet" ""
			(at 72.39 215.9 0)
			(effects
				(font
					(size 1.27 1.27)
					(thickness 0.15)
				)
				(justify left bottom)
				(hide yes)
			)
		)
		(property "Description" ""
			(at 81.28 203.2 0)
			(effects
				(font
					(size 1.27 1.27)
				)
			)
		)
		(property "Author" "Antmicro"
			(at 72.39 210.82 0)
			(effects
				(font
					(size 1.27 1.27)
					(thickness 0.15)
				)
				(justify left bottom)
				(hide yes)
			)
		)
		(property "License" "Apache-2.0"
			(at 72.39 213.36 0)
			(effects
				(font
					(size 1.27 1.27)
					(thickness 0.15)
				)
				(justify left bottom)
				(hide yes)
			)
		)
		(pin "1"
		)
		(instances
			(project "k410t-devboard"
				(path ""
					(reference "#PWR0209")
					(unit 1)
				)
			)
		)
	)
	(symbol
		(lib_id "antmicropower:+3.3V")
		(at 337.82 134.62 0)
		(unit 1)
		(exclude_from_sim no)
		(in_bom yes)
		(on_board yes)
		(dnp no)
		(property "Reference" "#PWR0235"
			(at 337.82 138.43 0)
			(effects
				(font
					(size 1.27 1.27)
				)
				(hide yes)
			)
		)
		(property "Value" "+3V3"
			(at 337.82 131.064 0)
			(effects
				(font
					(size 1.27 1.27)
				)
			)
		)
		(property "Footprint" ""
			(at 337.82 134.62 0)
			(effects
				(font
					(size 1.27 1.27)
				)
				(hide yes)
			)
		)
		(property "Datasheet" ""
			(at 337.82 134.62 0)
			(effects
				(font
					(size 1.27 1.27)
				)
				(hide yes)
			)
		)
		(property "Description" ""
			(at 337.82 134.62 0)
			(effects
				(font
					(size 1.27 1.27)
				)
			)
		)
		(pin "1"
		)
		(instances
			(project "k410t-devboard"
				(path ""
					(reference "#PWR0235")
					(unit 1)
				)
			)
		)
	)
	(symbol
		(lib_id "antmicroCapacitors0402:C_22p_0402")
		(at 127 92.71 90)
		(unit 1)
		(exclude_from_sim no)
		(in_bom yes)
		(on_board yes)
		(dnp no)
		(property "Reference" "C223"
			(at 127.635 88.265 90)
			(effects
				(font
					(size 1.27 1.27)
				)
				(justify right)
			)
		)
		(property "Value" "C_22p_0402"
			(at 137.16 72.39 0)
			(effects
				(font
					(size 1.27 1.27)
					(thickness 0.15)
				)
				(justify left bottom)
				(hide yes)
			)
		)
		(property "Footprint" "antmicro-footprints:C_0402_1005Metric"
			(at 139.7 72.39 0)
			(effects
				(font
					(size 1.27 1.27)
					(thickness 0.15)
				)
				(justify left bottom)
				(hide yes)
			)
		)
		(property "Datasheet" "https://www.yageo.com/en/Chart/Download/pdf/CC0402JRNPO9BN220"
			(at 142.24 72.39 0)
			(effects
				(font
					(size 1.27 1.27)
					(thickness 0.15)
				)
				(justify left bottom)
				(hide yes)
			)
		)
		(property "Description" ""
			(at 127 92.71 0)
			(effects
				(font
					(size 1.27 1.27)
				)
			)
		)
		(property "Manufacturer" "YAGEO"
			(at 147.32 72.39 0)
			(effects
				(font
					(size 1.27 1.27)
					(thickness 0.15)
				)
				(justify left bottom)
				(hide yes)
			)
		)
		(property "MPN" "CC0402JRNPO9BN220"
			(at 144.78 72.39 0)
			(effects
				(font
					(size 1.27 1.27)
					(thickness 0.15)
				)
				(justify left bottom)
				(hide yes)
			)
		)
		(property "Val" "22p"
			(at 127.635 92.075 90)
			(effects
				(font
					(size 1.27 1.27)
					(thickness 0.15)
				)
				(justify right)
			)
		)
		(property "License" "Apache-2.0"
			(at 149.86 72.39 0)
			(effects
				(font
					(size 1.27 1.27)
					(thickness 0.15)
				)
				(justify left bottom)
				(hide yes)
			)
		)
		(property "Author" "Antmicro"
			(at 152.4 72.39 0)
			(effects
				(font
					(size 1.27 1.27)
					(thickness 0.15)
				)
				(justify left bottom)
				(hide yes)
			)
		)
		(property "Voltage" ""
			(at 154.94 72.39 0)
			(effects
				(font
					(size 1.27 1.27)
				)
				(justify left bottom)
				(hide yes)
			)
		)
		(property "Dielectric" ""
			(at 157.48 72.39 0)
			(effects
				(font
					(size 1.27 1.27)
				)
				(justify left bottom)
				(hide yes)
			)
		)
		(pin "1"
		)
		(pin "2"
		)
		(instances
			(project "k410t-devboard"
				(path ""
					(reference "C223")
					(unit 1)
				)
			)
		)
	)
	(symbol
		(lib_id "antmicropower:+1V8")
		(at 405.13 44.45 0)
		(unit 1)
		(exclude_from_sim no)
		(in_bom yes)
		(on_board yes)
		(dnp no)
		(property "Reference" "#PWR0250"
			(at 405.13 48.26 0)
			(effects
				(font
					(size 1.27 1.27)
				)
				(hide yes)
			)
		)
		(property "Value" "+1V8"
			(at 405.13 40.894 0)
			(effects
				(font
					(size 1.27 1.27)
				)
			)
		)
		(property "Footprint" ""
			(at 420.37 52.07 0)
			(effects
				(font
					(size 1.27 1.27)
					(thickness 0.15)
				)
				(justify left bottom)
				(hide yes)
			)
		)
		(property "Datasheet" ""
			(at 420.37 54.61 0)
			(effects
				(font
					(size 1.27 1.27)
					(thickness 0.15)
				)
				(justify left bottom)
				(hide yes)
			)
		)
		(property "Description" ""
			(at 405.13 44.45 0)
			(effects
				(font
					(size 1.27 1.27)
				)
			)
		)
		(property "Author" "Antmicro"
			(at 420.37 52.07 0)
			(effects
				(font
					(size 1.27 1.27)
					(thickness 0.15)
				)
				(justify left bottom)
				(hide yes)
			)
		)
		(property "License" "Apache-2.0"
			(at 420.37 54.61 0)
			(effects
				(font
					(size 1.27 1.27)
					(thickness 0.15)
				)
				(justify left bottom)
				(hide yes)
			)
		)
		(pin "1"
		)
		(instances
			(project "k410t-devboard"
				(path ""
					(reference "#PWR0250")
					(unit 1)
				)
			)
		)
	)
	(symbol
		(lib_id "antmicropower:GND")
		(at 104.14 153.67 0)
		(unit 1)
		(exclude_from_sim no)
		(in_bom yes)
		(on_board yes)
		(dnp no)
		(property "Reference" "#PWR0212"
			(at 104.14 160.02 0)
			(effects
				(font
					(size 1.27 1.27)
				)
				(hide yes)
			)
		)
		(property "Value" "GND"
			(at 104.14 157.48 0)
			(effects
				(font
					(size 1.27 1.27)
				)
			)
		)
		(property "Footprint" ""
			(at 113.03 161.29 0)
			(effects
				(font
					(size 1.27 1.27)
					(thickness 0.15)
				)
				(justify left bottom)
				(hide yes)
			)
		)
		(property "Datasheet" ""
			(at 113.03 166.37 0)
			(effects
				(font
					(size 1.27 1.27)
					(thickness 0.15)
				)
				(justify left bottom)
				(hide yes)
			)
		)
		(property "Description" ""
			(at 104.14 153.67 0)
			(effects
				(font
					(size 1.27 1.27)
				)
			)
		)
		(property "Author" "Antmicro"
			(at 113.03 161.29 0)
			(effects
				(font
					(size 1.27 1.27)
					(thickness 0.15)
				)
				(justify left bottom)
				(hide yes)
			)
		)
		(property "License" "Apache-2.0"
			(at 113.03 163.83 0)
			(effects
				(font
					(size 1.27 1.27)
					(thickness 0.15)
				)
				(justify left bottom)
				(hide yes)
			)
		)
		(pin "1"
		)
		(instances
			(project "k410t-devboard"
				(path ""
					(reference "#PWR0212")
					(unit 1)
				)
			)
		)
	)
	(symbol
		(lib_id "antmicroCapacitors0402:C_1u_0402")
		(at 307.34 31.75 90)
		(unit 1)
		(exclude_from_sim no)
		(in_bom yes)
		(on_board yes)
		(dnp no)
		(property "Reference" "C243"
			(at 307.975 27.305 90)
			(effects
				(font
					(size 1.27 1.27)
				)
				(justify right)
			)
		)
		(property "Value" "C_1u_0402"
			(at 317.5 11.43 0)
			(effects
				(font
					(size 1.27 1.27)
					(thickness 0.15)
				)
				(justify left bottom)
				(hide yes)
			)
		)
		(property "Footprint" "antmicro-footprints:C_0402_1005Metric"
			(at 320.04 11.43 0)
			(effects
				(font
					(size 1.27 1.27)
					(thickness 0.15)
				)
				(justify left bottom)
				(hide yes)
			)
		)
		(property "Datasheet" "https://product.tdk.com/en/search/capacitor/ceramic/mlcc/info?part_no=C1005X6S1A105K050BC"
			(at 322.58 11.43 0)
			(effects
				(font
					(size 1.27 1.27)
					(thickness 0.15)
				)
				(justify left bottom)
				(hide yes)
			)
		)
		(property "Description" ""
			(at 307.34 31.75 0)
			(effects
				(font
					(size 1.27 1.27)
				)
			)
		)
		(property "Manufacturer" "TDK"
			(at 327.66 11.43 0)
			(effects
				(font
					(size 1.27 1.27)
					(thickness 0.15)
				)
				(justify left bottom)
				(hide yes)
			)
		)
		(property "MPN" "C1005X6S1A105K050BC"
			(at 325.12 11.43 0)
			(effects
				(font
					(size 1.27 1.27)
					(thickness 0.15)
				)
				(justify left bottom)
				(hide yes)
			)
		)
		(property "Val" "1u"
			(at 307.975 31.115 90)
			(effects
				(font
					(size 1.27 1.27)
					(thickness 0.15)
				)
				(justify right)
			)
		)
		(property "License" "Apache-2.0"
			(at 330.2 11.43 0)
			(effects
				(font
					(size 1.27 1.27)
					(thickness 0.15)
				)
				(justify left bottom)
				(hide yes)
			)
		)
		(property "Author" "Antmicro"
			(at 332.74 11.43 0)
			(effects
				(font
					(size 1.27 1.27)
					(thickness 0.15)
				)
				(justify left bottom)
				(hide yes)
			)
		)
		(property "Voltage" ""
			(at 335.28 11.43 0)
			(effects
				(font
					(size 1.27 1.27)
				)
				(justify left bottom)
				(hide yes)
			)
		)
		(property "Dielectric" ""
			(at 337.82 11.43 0)
			(effects
				(font
					(size 1.27 1.27)
				)
				(justify left bottom)
				(hide yes)
			)
		)
		(pin "1"
		)
		(pin "2"
		)
		(instances
			(project "k410t-devboard"
				(path ""
					(reference "C243")
					(unit 1)
				)
			)
		)
	)
	(symbol
		(lib_id "antmicropower:GND")
		(at 58.42 214.63 0)
		(unit 1)
		(exclude_from_sim no)
		(in_bom yes)
		(on_board yes)
		(dnp no)
		(property "Reference" "#PWR0203"
			(at 58.42 220.98 0)
			(effects
				(font
					(size 1.27 1.27)
				)
				(hide yes)
			)
		)
		(property "Value" "GND"
			(at 58.42 218.44 0)
			(effects
				(font
					(size 1.27 1.27)
				)
			)
		)
		(property "Footprint" ""
			(at 67.31 222.25 0)
			(effects
				(font
					(size 1.27 1.27)
					(thickness 0.15)
				)
				(justify left bottom)
				(hide yes)
			)
		)
		(property "Datasheet" ""
			(at 67.31 227.33 0)
			(effects
				(font
					(size 1.27 1.27)
					(thickness 0.15)
				)
				(justify left bottom)
				(hide yes)
			)
		)
		(property "Description" ""
			(at 58.42 214.63 0)
			(effects
				(font
					(size 1.27 1.27)
				)
			)
		)
		(property "Author" "Antmicro"
			(at 67.31 222.25 0)
			(effects
				(font
					(size 1.27 1.27)
					(thickness 0.15)
				)
				(justify left bottom)
				(hide yes)
			)
		)
		(property "License" "Apache-2.0"
			(at 67.31 224.79 0)
			(effects
				(font
					(size 1.27 1.27)
					(thickness 0.15)
				)
				(justify left bottom)
				(hide yes)
			)
		)
		(pin "1"
		)
		(instances
			(project "k410t-devboard"
				(path ""
					(reference "#PWR0203")
					(unit 1)
				)
			)
		)
	)
	(symbol
		(lib_id "antmicroResistors0402:R_10k_0402")
		(at 137.16 232.41 90)
		(mirror x)
		(unit 1)
		(exclude_from_sim no)
		(in_bom yes)
		(on_board yes)
		(dnp no)
		(property "Reference" "R158"
			(at 138.43 233.68 90)
			(effects
				(font
					(size 1.27 1.27)
				)
				(justify right)
			)
		)
		(property "Value" "R_10k_0402"
			(at 149.86 252.73 0)
			(effects
				(font
					(size 1.27 1.27)
					(thickness 0.15)
				)
				(justify left bottom)
				(hide yes)
			)
		)
		(property "Footprint" "antmicro-footprints:R_0402_1005Metric"
			(at 152.4 252.73 0)
			(effects
				(font
					(size 1.27 1.27)
					(thickness 0.15)
				)
				(justify left bottom)
				(hide yes)
			)
		)
		(property "Datasheet" "https://www.bourns.com/docs/product-datasheets/cr.pdf"
			(at 154.94 252.73 0)
			(effects
				(font
					(size 1.27 1.27)
					(thickness 0.15)
				)
				(justify left bottom)
				(hide yes)
			)
		)
		(property "Description" ""
			(at 137.16 232.41 0)
			(effects
				(font
					(size 1.27 1.27)
				)
			)
		)
		(property "Manufacturer" "Bourns"
			(at 160.02 252.73 0)
			(effects
				(font
					(size 1.27 1.27)
					(thickness 0.15)
				)
				(justify left bottom)
				(hide yes)
			)
		)
		(property "MPN" "CR0402-FX-1002GLF"
			(at 157.48 252.73 0)
			(effects
				(font
					(size 1.27 1.27)
					(thickness 0.15)
				)
				(justify left bottom)
				(hide yes)
			)
		)
		(property "Val" "10k"
			(at 138.43 236.22 90)
			(effects
				(font
					(size 1.27 1.27)
					(thickness 0.15)
				)
				(justify right)
			)
		)
		(property "License" "Apache-2.0"
			(at 162.56 252.73 0)
			(effects
				(font
					(size 1.27 1.27)
					(thickness 0.15)
				)
				(justify left bottom)
				(hide yes)
			)
		)
		(property "Author" "Antmicro"
			(at 165.1 252.73 0)
			(effects
				(font
					(size 1.27 1.27)
					(thickness 0.15)
				)
				(justify left bottom)
				(hide yes)
			)
		)
		(property "Tolerance" "1%"
			(at 147.32 252.73 0)
			(effects
				(font
					(size 1.27 1.27)
				)
				(justify left bottom)
				(hide yes)
			)
		)
		(pin "1"
		)
		(pin "2"
		)
		(instances
			(project "k410t-devboard"
				(path ""
					(reference "R158")
					(unit 1)
				)
			)
		)
	)
	(symbol
		(lib_id "antmicroUSBConnectors:USB-C_GCT_USB4105-GF-A")
		(at 55.88 176.53 0)
		(unit 1)
		(exclude_from_sim no)
		(in_bom yes)
		(on_board yes)
		(dnp no)
		(fields_autoplaced yes)
		(property "Reference" "J13"
			(at 42.545 168.91 0)
			(effects
				(font
					(size 1.27 1.27)
					(thickness 0.15)
				)
			)
		)
		(property "Value" "USB-C_GCT_USB4105-GF-A"
			(at 66.3575 172.085 0)
			(effects
				(font
					(size 1.27 1.27)
					(thickness 0.15)
				)
				(hide yes)
			)
		)
		(property "Footprint" "antmicro-footprints:USB-C_Receptacle_GCT_USB4105-GF-A"
			(at 93.98 184.15 0)
			(effects
				(font
					(size 1.27 1.27)
					(thickness 0.15)
				)
				(justify left bottom)
				(hide yes)
			)
		)
		(property "Datasheet" "https://gct.co/files/drawings/usb4105.pdf"
			(at 93.98 186.69 0)
			(effects
				(font
					(size 1.27 1.27)
					(thickness 0.15)
				)
				(justify left bottom)
				(hide yes)
			)
		)
		(property "Description" ""
			(at 55.88 176.53 0)
			(effects
				(font
					(size 1.27 1.27)
				)
			)
		)
		(property "Manufacturer" "GCT"
			(at 93.98 189.23 0)
			(effects
				(font
					(size 1.27 1.27)
					(thickness 0.15)
				)
				(justify left bottom)
				(hide yes)
			)
		)
		(property "MPN" "USB4105-GF-A"
			(at 42.545 171.45 0)
			(effects
				(font
					(size 1.27 1.27)
					(thickness 0.15)
				)
			)
		)
		(property "Author" "Antmicro"
			(at 93.98 194.31 0)
			(effects
				(font
					(size 1.27 1.27)
					(thickness 0.15)
				)
				(justify left bottom)
				(hide yes)
			)
		)
		(property "License" "Apache-2.0"
			(at 93.98 196.85 0)
			(effects
				(font
					(size 1.27 1.27)
					(thickness 0.15)
				)
				(justify left bottom)
				(hide yes)
			)
		)
		(property "VSD_Class" "USB-C"
			(at 93.98 199.39 0)
			(effects
				(font
					(size 1.27 1.27)
				)
				(justify left bottom)
				(hide yes)
			)
		)
		(pin "A1"
		)
		(pin "A12"
		)
		(pin "A4"
		)
		(pin "A5"
		)
		(pin "A6"
		)
		(pin "A7"
		)
		(pin "A8"
		)
		(pin "A9"
		)
		(pin "B1"
		)
		(pin "B12"
		)
		(pin "B4"
		)
		(pin "B5"
		)
		(pin "B6"
		)
		(pin "B7"
		)
		(pin "B8"
		)
		(pin "B9"
		)
		(pin "SH"
		)
		(instances
			(project "k410t-devboard"
				(path ""
					(reference "J13")
					(unit 1)
				)
			)
		)
	)
	(symbol
		(lib_id "antmicropower:+5V")
		(at 46.99 67.31 0)
		(unit 1)
		(exclude_from_sim no)
		(in_bom yes)
		(on_board yes)
		(dnp no)
		(property "Reference" "#PWR0372"
			(at 46.99 71.12 0)
			(effects
				(font
					(size 1.27 1.27)
				)
				(hide yes)
			)
		)
		(property "Value" "+5V"
			(at 46.99 63.5 0)
			(effects
				(font
					(size 1.27 1.27)
				)
			)
		)
		(property "Footprint" ""
			(at 46.99 67.31 0)
			(effects
				(font
					(size 1.27 1.27)
				)
				(hide yes)
			)
		)
		(property "Datasheet" ""
			(at 46.99 67.31 0)
			(effects
				(font
					(size 1.27 1.27)
				)
				(hide yes)
			)
		)
		(property "Description" ""
			(at 46.99 67.31 0)
			(effects
				(font
					(size 1.27 1.27)
				)
			)
		)
		(property "Author" "Antmicro"
			(at 62.23 74.93 0)
			(effects
				(font
					(size 1.27 1.27)
					(thickness 0.15)
				)
				(justify left bottom)
				(hide yes)
			)
		)
		(property "License" "Apache-2.0"
			(at 62.23 77.47 0)
			(effects
				(font
					(size 1.27 1.27)
					(thickness 0.15)
				)
				(justify left bottom)
				(hide yes)
			)
		)
		(pin "1"
		)
		(instances
			(project "k410t-devboard"
				(path ""
					(reference "#PWR0372")
					(unit 1)
				)
			)
		)
	)
	(symbol
		(lib_id "antmicroCapacitors0402:C_10u_0402")
		(at 64.77 140.97 90)
		(unit 1)
		(exclude_from_sim no)
		(in_bom yes)
		(on_board yes)
		(dnp no)
		(fields_autoplaced yes)
		(property "Reference" "C221"
			(at 67.31 137.1535 90)
			(effects
				(font
					(size 1.27 1.27)
				)
				(justify right)
			)
		)
		(property "Value" "C_10u_0402"
			(at 74.93 120.65 0)
			(effects
				(font
					(size 1.27 1.27)
					(thickness 0.15)
				)
				(justify left bottom)
				(hide yes)
			)
		)
		(property "Footprint" "antmicro-footprints:C_0402_1005Metric"
			(at 77.47 120.65 0)
			(effects
				(font
					(size 1.27 1.27)
					(thickness 0.15)
				)
				(justify left bottom)
				(hide yes)
			)
		)
		(property "Datasheet" "https://www.yageo.com/en/Chart/Download/pdf/CC0402MRX5R5BB106"
			(at 80.01 120.65 0)
			(effects
				(font
					(size 1.27 1.27)
					(thickness 0.15)
				)
				(justify left bottom)
				(hide yes)
			)
		)
		(property "Description" ""
			(at 64.77 140.97 0)
			(effects
				(font
					(size 1.27 1.27)
				)
			)
		)
		(property "Manufacturer" "YAGEO"
			(at 85.09 120.65 0)
			(effects
				(font
					(size 1.27 1.27)
					(thickness 0.15)
				)
				(justify left bottom)
				(hide yes)
			)
		)
		(property "MPN" "CC0402MRX5R5BB106"
			(at 82.55 120.65 0)
			(effects
				(font
					(size 1.27 1.27)
					(thickness 0.15)
				)
				(justify left bottom)
				(hide yes)
			)
		)
		(property "Val" "10u"
			(at 67.31 139.6935 90)
			(effects
				(font
					(size 1.27 1.27)
					(thickness 0.15)
				)
				(justify right)
			)
		)
		(property "License" "Apache-2.0"
			(at 87.63 120.65 0)
			(effects
				(font
					(size 1.27 1.27)
					(thickness 0.15)
				)
				(justify left bottom)
				(hide yes)
			)
		)
		(property "Author" "Antmicro"
			(at 90.17 120.65 0)
			(effects
				(font
					(size 1.27 1.27)
					(thickness 0.15)
				)
				(justify left bottom)
				(hide yes)
			)
		)
		(property "Voltage" ""
			(at 92.71 120.65 0)
			(effects
				(font
					(size 1.27 1.27)
				)
				(justify left bottom)
				(hide yes)
			)
		)
		(property "Dielectric" ""
			(at 95.25 120.65 0)
			(effects
				(font
					(size 1.27 1.27)
				)
				(justify left bottom)
				(hide yes)
			)
		)
		(pin "1"
		)
		(pin "2"
		)
		(instances
			(project "k410t-devboard"
				(path ""
					(reference "C221")
					(unit 1)
				)
			)
		)
	)
	(symbol
		(lib_id "antmicropower:+3.3V")
		(at 270.51 135.89 0)
		(unit 1)
		(exclude_from_sim no)
		(in_bom yes)
		(on_board yes)
		(dnp no)
		(fields_autoplaced yes)
		(property "Reference" "#PWR0512"
			(at 270.51 139.7 0)
			(effects
				(font
					(size 1.27 1.27)
				)
				(hide yes)
			)
		)
		(property "Value" "+3V3"
			(at 270.51 132.334 0)
			(effects
				(font
					(size 1.27 1.27)
				)
			)
		)
		(property "Footprint" ""
			(at 270.51 135.89 0)
			(effects
				(font
					(size 1.27 1.27)
				)
				(hide yes)
			)
		)
		(property "Datasheet" ""
			(at 270.51 135.89 0)
			(effects
				(font
					(size 1.27 1.27)
				)
				(hide yes)
			)
		)
		(property "Description" ""
			(at 270.51 135.89 0)
			(effects
				(font
					(size 1.27 1.27)
				)
			)
		)
		(pin "1"
		)
		(instances
			(project "k410t-devboard"
				(path ""
					(reference "#PWR0512")
					(unit 1)
				)
			)
		)
	)
	(symbol
		(lib_id "antmicroCapacitors0402:C_100n_0402")
		(at 173.99 133.35 90)
		(unit 1)
		(exclude_from_sim no)
		(in_bom yes)
		(on_board yes)
		(dnp no)
		(property "Reference" "C239"
			(at 174.625 128.905 90)
			(effects
				(font
					(size 1.27 1.27)
				)
				(justify right)
			)
		)
		(property "Value" "C_100n_0402"
			(at 184.15 113.03 0)
			(effects
				(font
					(size 1.27 1.27)
					(thickness 0.15)
				)
				(justify left bottom)
				(hide yes)
			)
		)
		(property "Footprint" "antmicro-footprints:C_0402_1005Metric"
			(at 186.69 113.03 0)
			(effects
				(font
					(size 1.27 1.27)
					(thickness 0.15)
				)
				(justify left bottom)
				(hide yes)
			)
		)
		(property "Datasheet" "https://www.murata.com/products/productdetail?partno=GRM155R61H104KE14%23"
			(at 189.23 113.03 0)
			(effects
				(font
					(size 1.27 1.27)
					(thickness 0.15)
				)
				(justify left bottom)
				(hide yes)
			)
		)
		(property "Description" ""
			(at 173.99 133.35 0)
			(effects
				(font
					(size 1.27 1.27)
				)
			)
		)
		(property "Manufacturer" "Murata"
			(at 194.31 113.03 0)
			(effects
				(font
					(size 1.27 1.27)
					(thickness 0.15)
				)
				(justify left bottom)
				(hide yes)
			)
		)
		(property "MPN" "GRM155R61H104KE14D"
			(at 191.77 113.03 0)
			(effects
				(font
					(size 1.27 1.27)
					(thickness 0.15)
				)
				(justify left bottom)
				(hide yes)
			)
		)
		(property "Val" "100n"
			(at 174.625 132.715 90)
			(effects
				(font
					(size 1.27 1.27)
					(thickness 0.15)
				)
				(justify right)
			)
		)
		(property "License" "Apache-2.0"
			(at 196.85 113.03 0)
			(effects
				(font
					(size 1.27 1.27)
					(thickness 0.15)
				)
				(justify left bottom)
				(hide yes)
			)
		)
		(property "Author" "Antmicro"
			(at 199.39 113.03 0)
			(effects
				(font
					(size 1.27 1.27)
					(thickness 0.15)
				)
				(justify left bottom)
				(hide yes)
			)
		)
		(property "Voltage" "50V"
			(at 201.93 113.03 0)
			(effects
				(font
					(size 1.27 1.27)
				)
				(justify left bottom)
				(hide yes)
			)
		)
		(property "Dielectric" "X5R"
			(at 204.47 113.03 0)
			(effects
				(font
					(size 1.27 1.27)
				)
				(justify left bottom)
				(hide yes)
			)
		)
		(pin "1"
		)
		(pin "2"
		)
		(instances
			(project "k410t-devboard"
				(path ""
					(reference "C239")
					(unit 1)
				)
			)
		)
	)
	(symbol
		(lib_id "antmicroCapacitors0402:C_100n_0402")
		(at 116.84 175.26 90)
		(unit 1)
		(exclude_from_sim no)
		(in_bom yes)
		(on_board yes)
		(dnp no)
		(property "Reference" "C238"
			(at 117.475 170.815 90)
			(effects
				(font
					(size 1.27 1.27)
				)
				(justify right)
			)
		)
		(property "Value" "C_100n_0402"
			(at 127 154.94 0)
			(effects
				(font
					(size 1.27 1.27)
					(thickness 0.15)
				)
				(justify left bottom)
				(hide yes)
			)
		)
		(property "Footprint" "antmicro-footprints:C_0402_1005Metric"
			(at 129.54 154.94 0)
			(effects
				(font
					(size 1.27 1.27)
					(thickness 0.15)
				)
				(justify left bottom)
				(hide yes)
			)
		)
		(property "Datasheet" "https://www.murata.com/products/productdetail?partno=GRM155R61H104KE14%23"
			(at 132.08 154.94 0)
			(effects
				(font
					(size 1.27 1.27)
					(thickness 0.15)
				)
				(justify left bottom)
				(hide yes)
			)
		)
		(property "Description" ""
			(at 116.84 175.26 0)
			(effects
				(font
					(size 1.27 1.27)
				)
			)
		)
		(property "Manufacturer" "Murata"
			(at 137.16 154.94 0)
			(effects
				(font
					(size 1.27 1.27)
					(thickness 0.15)
				)
				(justify left bottom)
				(hide yes)
			)
		)
		(property "MPN" "GRM155R61H104KE14D"
			(at 134.62 154.94 0)
			(effects
				(font
					(size 1.27 1.27)
					(thickness 0.15)
				)
				(justify left bottom)
				(hide yes)
			)
		)
		(property "Val" "100n"
			(at 117.475 174.625 90)
			(effects
				(font
					(size 1.27 1.27)
					(thickness 0.15)
				)
				(justify right)
			)
		)
		(property "License" "Apache-2.0"
			(at 139.7 154.94 0)
			(effects
				(font
					(size 1.27 1.27)
					(thickness 0.15)
				)
				(justify left bottom)
				(hide yes)
			)
		)
		(property "Author" "Antmicro"
			(at 142.24 154.94 0)
			(effects
				(font
					(size 1.27 1.27)
					(thickness 0.15)
				)
				(justify left bottom)
				(hide yes)
			)
		)
		(property "Voltage" "50V"
			(at 144.78 154.94 0)
			(effects
				(font
					(size 1.27 1.27)
				)
				(justify left bottom)
				(hide yes)
			)
		)
		(property "Dielectric" "X5R"
			(at 147.32 154.94 0)
			(effects
				(font
					(size 1.27 1.27)
				)
				(justify left bottom)
				(hide yes)
			)
		)
		(pin "1"
		)
		(pin "2"
		)
		(instances
			(project "k410t-devboard"
				(path ""
					(reference "C238")
					(unit 1)
				)
			)
		)
	)
	(symbol
		(lib_id "antmicroPMICVoltageRegulatorsLinear:NCP718BSN330T1G")
		(at 38.1 133.35 0)
		(unit 1)
		(exclude_from_sim no)
		(in_bom yes)
		(on_board yes)
		(dnp no)
		(fields_autoplaced yes)
		(property "Reference" "U15"
			(at 48.26 125.73 0)
			(effects
				(font
					(size 1.27 1.27)
				)
			)
		)
		(property "Value" "NCP718BSN330T1G"
			(at 48.26 128.27 0)
			(effects
				(font
					(size 1.27 1.27)
					(thickness 0.15)
				)
				(hide yes)
			)
		)
		(property "Footprint" "antmicro-footprints:SOT-23-5"
			(at 73.66 142.24 0)
			(effects
				(font
					(size 1.27 1.27)
					(thickness 0.15)
				)
				(justify left bottom)
				(hide yes)
			)
		)
		(property "Datasheet" "https://www.mouser.com/datasheet/2/308/NCP718_D-1224359.pdf"
			(at 73.66 144.78 0)
			(effects
				(font
					(size 1.27 1.27)
					(thickness 0.15)
				)
				(justify left bottom)
				(hide yes)
			)
		)
		(property "Description" ""
			(at 38.1 133.35 0)
			(effects
				(font
					(size 1.27 1.27)
				)
			)
		)
		(property "MPN" "NCP718BSN330T1G"
			(at 73.66 147.32 0)
			(effects
				(font
					(size 1.27 1.27)
					(thickness 0.15)
				)
				(justify left bottom)
			)
		)
		(property "Manufacturer" "ON Semiconductor"
			(at 73.66 149.86 0)
			(effects
				(font
					(size 1.27 1.27)
					(thickness 0.15)
				)
				(justify left bottom)
				(hide yes)
			)
		)
		(property "Author" "Antmicro"
			(at 73.66 152.4 0)
			(effects
				(font
					(size 1.27 1.27)
					(thickness 0.15)
				)
				(justify left bottom)
				(hide yes)
			)
		)
		(property "License" "Apache-2.0"
			(at 73.66 154.94 0)
			(effects
				(font
					(size 1.27 1.27)
					(thickness 0.15)
				)
				(justify left bottom)
				(hide yes)
			)
		)
		(pin "1"
		)
		(pin "2"
		)
		(pin "3"
		)
		(pin "4"
		)
		(pin "5"
		)
		(instances
			(project "k410t-devboard"
				(path ""
					(reference "U15")
					(unit 1)
				)
			)
		)
	)
	(symbol
		(lib_id "antmicropower:GND")
		(at 341.63 246.38 0)
		(unit 1)
		(exclude_from_sim no)
		(in_bom yes)
		(on_board yes)
		(dnp no)
		(property "Reference" "#PWR0269"
			(at 341.63 252.73 0)
			(effects
				(font
					(size 1.27 1.27)
				)
				(hide yes)
			)
		)
		(property "Value" "GND"
			(at 341.63 250.19 0)
			(effects
				(font
					(size 1.27 1.27)
				)
			)
		)
		(property "Footprint" ""
			(at 350.52 254 0)
			(effects
				(font
					(size 1.27 1.27)
					(thickness 0.15)
				)
				(justify left bottom)
				(hide yes)
			)
		)
		(property "Datasheet" ""
			(at 350.52 259.08 0)
			(effects
				(font
					(size 1.27 1.27)
					(thickness 0.15)
				)
				(justify left bottom)
				(hide yes)
			)
		)
		(property "Description" ""
			(at 341.63 246.38 0)
			(effects
				(font
					(size 1.27 1.27)
				)
			)
		)
		(property "Author" "Antmicro"
			(at 350.52 254 0)
			(effects
				(font
					(size 1.27 1.27)
					(thickness 0.15)
				)
				(justify left bottom)
				(hide yes)
			)
		)
		(property "License" "Apache-2.0"
			(at 350.52 256.54 0)
			(effects
				(font
					(size 1.27 1.27)
					(thickness 0.15)
				)
				(justify left bottom)
				(hide yes)
			)
		)
		(pin "1"
		)
		(instances
			(project "k410t-devboard"
				(path ""
					(reference "#PWR0269")
					(unit 1)
				)
			)
		)
	)
	(symbol
		(lib_id "antmicropower:+1V8")
		(at 355.6 22.86 0)
		(unit 1)
		(exclude_from_sim no)
		(in_bom yes)
		(on_board yes)
		(dnp no)
		(property "Reference" "#PWR0240"
			(at 355.6 26.67 0)
			(effects
				(font
					(size 1.27 1.27)
				)
				(hide yes)
			)
		)
		(property "Value" "+1V8"
			(at 355.6 19.304 0)
			(effects
				(font
					(size 1.27 1.27)
				)
			)
		)
		(property "Footprint" ""
			(at 370.84 30.48 0)
			(effects
				(font
					(size 1.27 1.27)
					(thickness 0.15)
				)
				(justify left bottom)
				(hide yes)
			)
		)
		(property "Datasheet" ""
			(at 370.84 33.02 0)
			(effects
				(font
					(size 1.27 1.27)
					(thickness 0.15)
				)
				(justify left bottom)
				(hide yes)
			)
		)
		(property "Description" ""
			(at 355.6 22.86 0)
			(effects
				(font
					(size 1.27 1.27)
				)
			)
		)
		(property "Author" "Antmicro"
			(at 370.84 30.48 0)
			(effects
				(font
					(size 1.27 1.27)
					(thickness 0.15)
				)
				(justify left bottom)
				(hide yes)
			)
		)
		(property "License" "Apache-2.0"
			(at 370.84 33.02 0)
			(effects
				(font
					(size 1.27 1.27)
					(thickness 0.15)
				)
				(justify left bottom)
				(hide yes)
			)
		)
		(pin "1"
		)
		(instances
			(project "k410t-devboard"
				(path ""
					(reference "#PWR0240")
					(unit 1)
				)
			)
		)
	)
	(symbol
		(lib_id "antmicroCapacitors0402:C_100n_0402")
		(at 125.73 133.35 90)
		(unit 1)
		(exclude_from_sim no)
		(in_bom yes)
		(on_board yes)
		(dnp no)
		(property "Reference" "C232"
			(at 126.365 128.905 90)
			(effects
				(font
					(size 1.27 1.27)
				)
				(justify right)
			)
		)
		(property "Value" "C_100n_0402"
			(at 135.89 113.03 0)
			(effects
				(font
					(size 1.27 1.27)
					(thickness 0.15)
				)
				(justify left bottom)
				(hide yes)
			)
		)
		(property "Footprint" "antmicro-footprints:C_0402_1005Metric"
			(at 138.43 113.03 0)
			(effects
				(font
					(size 1.27 1.27)
					(thickness 0.15)
				)
				(justify left bottom)
				(hide yes)
			)
		)
		(property "Datasheet" "https://www.murata.com/products/productdetail?partno=GRM155R61H104KE14%23"
			(at 140.97 113.03 0)
			(effects
				(font
					(size 1.27 1.27)
					(thickness 0.15)
				)
				(justify left bottom)
				(hide yes)
			)
		)
		(property "Description" ""
			(at 125.73 133.35 0)
			(effects
				(font
					(size 1.27 1.27)
				)
			)
		)
		(property "Manufacturer" "Murata"
			(at 146.05 113.03 0)
			(effects
				(font
					(size 1.27 1.27)
					(thickness 0.15)
				)
				(justify left bottom)
				(hide yes)
			)
		)
		(property "MPN" "GRM155R61H104KE14D"
			(at 143.51 113.03 0)
			(effects
				(font
					(size 1.27 1.27)
					(thickness 0.15)
				)
				(justify left bottom)
				(hide yes)
			)
		)
		(property "Val" "100n"
			(at 126.365 132.715 90)
			(effects
				(font
					(size 1.27 1.27)
					(thickness 0.15)
				)
				(justify right)
			)
		)
		(property "License" "Apache-2.0"
			(at 148.59 113.03 0)
			(effects
				(font
					(size 1.27 1.27)
					(thickness 0.15)
				)
				(justify left bottom)
				(hide yes)
			)
		)
		(property "Author" "Antmicro"
			(at 151.13 113.03 0)
			(effects
				(font
					(size 1.27 1.27)
					(thickness 0.15)
				)
				(justify left bottom)
				(hide yes)
			)
		)
		(property "Voltage" "50V"
			(at 153.67 113.03 0)
			(effects
				(font
					(size 1.27 1.27)
				)
				(justify left bottom)
				(hide yes)
			)
		)
		(property "Dielectric" "X5R"
			(at 156.21 113.03 0)
			(effects
				(font
					(size 1.27 1.27)
				)
				(justify left bottom)
				(hide yes)
			)
		)
		(pin "1"
		)
		(pin "2"
		)
		(instances
			(project "k410t-devboard"
				(path ""
					(reference "C232")
					(unit 1)
				)
			)
		)
	)
	(symbol
		(lib_id "antmicropower:PWR_FLAG")
		(at 104.14 165.1 0)
		(unit 1)
		(exclude_from_sim no)
		(in_bom yes)
		(on_board yes)
		(dnp no)
		(property "Reference" "#FLG08"
			(at 104.14 163.195 0)
			(effects
				(font
					(size 1.27 1.27)
				)
				(hide yes)
			)
		)
		(property "Value" "PWR_FLAG"
			(at 104.14 161.29 0)
			(effects
				(font
					(size 1.27 1.27)
				)
			)
		)
		(property "Footprint" ""
			(at 104.14 165.1 0)
			(effects
				(font
					(size 1.27 1.27)
				)
				(hide yes)
			)
		)
		(property "Datasheet" ""
			(at 104.14 165.1 0)
			(effects
				(font
					(size 1.27 1.27)
				)
				(hide yes)
			)
		)
		(property "Description" ""
			(at 104.14 165.1 0)
			(effects
				(font
					(size 1.27 1.27)
				)
			)
		)
		(pin "1"
		)
		(instances
			(project "k410t-devboard"
				(path ""
					(reference "#FLG08")
					(unit 1)
				)
			)
		)
	)
	(symbol
		(lib_id "antmicroCapacitors0402:C_100n_0402")
		(at 88.9 91.44 90)
		(unit 1)
		(exclude_from_sim no)
		(in_bom yes)
		(on_board yes)
		(dnp no)
		(property "Reference" "C394"
			(at 89.535 86.995 90)
			(effects
				(font
					(size 1.27 1.27)
				)
				(justify right)
			)
		)
		(property "Value" "C_100n_0402"
			(at 99.06 71.12 0)
			(effects
				(font
					(size 1.27 1.27)
					(thickness 0.15)
				)
				(justify left bottom)
				(hide yes)
			)
		)
		(property "Footprint" "antmicro-footprints:C_0402_1005Metric"
			(at 101.6 71.12 0)
			(effects
				(font
					(size 1.27 1.27)
					(thickness 0.15)
				)
				(justify left bottom)
				(hide yes)
			)
		)
		(property "Datasheet" "https://www.murata.com/products/productdetail?partno=GRM155R61H104KE14%23"
			(at 104.14 71.12 0)
			(effects
				(font
					(size 1.27 1.27)
					(thickness 0.15)
				)
				(justify left bottom)
				(hide yes)
			)
		)
		(property "Description" ""
			(at 88.9 91.44 0)
			(effects
				(font
					(size 1.27 1.27)
				)
			)
		)
		(property "Manufacturer" "Murata"
			(at 109.22 71.12 0)
			(effects
				(font
					(size 1.27 1.27)
					(thickness 0.15)
				)
				(justify left bottom)
				(hide yes)
			)
		)
		(property "MPN" "GRM155R61H104KE14D"
			(at 106.68 71.12 0)
			(effects
				(font
					(size 1.27 1.27)
					(thickness 0.15)
				)
				(justify left bottom)
				(hide yes)
			)
		)
		(property "Val" "100n"
			(at 89.535 90.805 90)
			(effects
				(font
					(size 1.27 1.27)
					(thickness 0.15)
				)
				(justify right)
			)
		)
		(property "License" "Apache-2.0"
			(at 111.76 71.12 0)
			(effects
				(font
					(size 1.27 1.27)
					(thickness 0.15)
				)
				(justify left bottom)
				(hide yes)
			)
		)
		(property "Author" "Antmicro"
			(at 114.3 71.12 0)
			(effects
				(font
					(size 1.27 1.27)
					(thickness 0.15)
				)
				(justify left bottom)
				(hide yes)
			)
		)
		(property "Voltage" "50V"
			(at 116.84 71.12 0)
			(effects
				(font
					(size 1.27 1.27)
				)
				(justify left bottom)
				(hide yes)
			)
		)
		(property "Dielectric" "X5R"
			(at 119.38 71.12 0)
			(effects
				(font
					(size 1.27 1.27)
				)
				(justify left bottom)
				(hide yes)
			)
		)
		(pin "1"
		)
		(pin "2"
		)
		(instances
			(project "k410t-devboard"
				(path ""
					(reference "C394")
					(unit 1)
				)
			)
		)
	)
	(symbol
		(lib_id "antmicroCapacitors0603:C_10u_25V_0603")
		(at 63.5 172.72 90)
		(unit 1)
		(exclude_from_sim no)
		(in_bom yes)
		(on_board yes)
		(dnp no)
		(fields_autoplaced yes)
		(property "Reference" "C222"
			(at 66.675 168.9035 90)
			(effects
				(font
					(size 1.27 1.27)
				)
				(justify right)
			)
		)
		(property "Value" "C_10u_25V_0603"
			(at 73.66 152.4 0)
			(effects
				(font
					(size 1.27 1.27)
					(thickness 0.15)
				)
				(justify left bottom)
				(hide yes)
			)
		)
		(property "Footprint" "antmicro-footprints:C_0603_1608Metric"
			(at 76.2 152.4 0)
			(effects
				(font
					(size 1.27 1.27)
					(thickness 0.15)
				)
				(justify left bottom)
				(hide yes)
			)
		)
		(property "Datasheet" "https://product.tdk.com/en/search/capacitor/ceramic/mlcc/info?part_no=C1608X5R1E106M080AC"
			(at 78.74 152.4 0)
			(effects
				(font
					(size 1.27 1.27)
					(thickness 0.15)
				)
				(justify left bottom)
				(hide yes)
			)
		)
		(property "Description" ""
			(at 63.5 172.72 0)
			(effects
				(font
					(size 1.27 1.27)
				)
			)
		)
		(property "Manufacturer" "TDK"
			(at 83.82 152.4 0)
			(effects
				(font
					(size 1.27 1.27)
					(thickness 0.15)
				)
				(justify left bottom)
				(hide yes)
			)
		)
		(property "MPN" "C1608X5R1E106M080AC"
			(at 81.28 152.4 0)
			(effects
				(font
					(size 1.27 1.27)
					(thickness 0.15)
				)
				(justify left bottom)
				(hide yes)
			)
		)
		(property "Val" "10u"
			(at 66.675 171.4435 90)
			(effects
				(font
					(size 1.27 1.27)
					(thickness 0.15)
				)
				(justify right)
			)
		)
		(property "License" "Apache-2.0"
			(at 86.36 152.4 0)
			(effects
				(font
					(size 1.27 1.27)
					(thickness 0.15)
				)
				(justify left bottom)
				(hide yes)
			)
		)
		(property "Author" "Antmicro"
			(at 88.9 152.4 0)
			(effects
				(font
					(size 1.27 1.27)
					(thickness 0.15)
				)
				(justify left bottom)
				(hide yes)
			)
		)
		(property "Voltage" "25V"
			(at 91.44 152.4 0)
			(effects
				(font
					(size 1.27 1.27)
				)
				(justify left bottom)
				(hide yes)
			)
		)
		(property "Dielectric" ""
			(at 93.98 152.4 0)
			(effects
				(font
					(size 1.27 1.27)
				)
				(justify left bottom)
				(hide yes)
			)
		)
		(pin "1"
		)
		(pin "2"
		)
		(instances
			(project "k410t-devboard"
				(path ""
					(reference "C222")
					(unit 1)
				)
			)
		)
	)
	(symbol
		(lib_id "antmicropower:GND")
		(at 125.73 134.62 0)
		(mirror y)
		(unit 1)
		(exclude_from_sim no)
		(in_bom yes)
		(on_board yes)
		(dnp no)
		(property "Reference" "#PWR0220"
			(at 125.73 140.97 0)
			(effects
				(font
					(size 1.27 1.27)
				)
				(hide yes)
			)
		)
		(property "Value" "GND"
			(at 127.635 138.43 0)
			(effects
				(font
					(size 1.27 1.27)
				)
				(justify left)
			)
		)
		(property "Footprint" ""
			(at 116.84 142.24 0)
			(effects
				(font
					(size 1.27 1.27)
					(thickness 0.15)
				)
				(justify left bottom)
				(hide yes)
			)
		)
		(property "Datasheet" ""
			(at 116.84 147.32 0)
			(effects
				(font
					(size 1.27 1.27)
					(thickness 0.15)
				)
				(justify left bottom)
				(hide yes)
			)
		)
		(property "Description" ""
			(at 125.73 134.62 0)
			(effects
				(font
					(size 1.27 1.27)
				)
			)
		)
		(property "Author" "Antmicro"
			(at 116.84 142.24 0)
			(effects
				(font
					(size 1.27 1.27)
					(thickness 0.15)
				)
				(justify left bottom)
				(hide yes)
			)
		)
		(property "License" "Apache-2.0"
			(at 116.84 144.78 0)
			(effects
				(font
					(size 1.27 1.27)
					(thickness 0.15)
				)
				(justify left bottom)
				(hide yes)
			)
		)
		(pin "1"
		)
		(instances
			(project "k410t-devboard"
				(path ""
					(reference "#PWR0220")
					(unit 1)
				)
			)
		)
	)
	(symbol
		(lib_id "antmicropower:GND")
		(at 116.84 176.53 0)
		(mirror y)
		(unit 1)
		(exclude_from_sim no)
		(in_bom yes)
		(on_board yes)
		(dnp no)
		(property "Reference" "#PWR0218"
			(at 116.84 182.88 0)
			(effects
				(font
					(size 1.27 1.27)
				)
				(hide yes)
			)
		)
		(property "Value" "GND"
			(at 116.84 180.34 0)
			(effects
				(font
					(size 1.27 1.27)
				)
			)
		)
		(property "Footprint" ""
			(at 107.95 184.15 0)
			(effects
				(font
					(size 1.27 1.27)
					(thickness 0.15)
				)
				(justify left bottom)
				(hide yes)
			)
		)
		(property "Datasheet" ""
			(at 107.95 189.23 0)
			(effects
				(font
					(size 1.27 1.27)
					(thickness 0.15)
				)
				(justify left bottom)
				(hide yes)
			)
		)
		(property "Description" ""
			(at 116.84 176.53 0)
			(effects
				(font
					(size 1.27 1.27)
				)
			)
		)
		(property "Author" "Antmicro"
			(at 107.95 184.15 0)
			(effects
				(font
					(size 1.27 1.27)
					(thickness 0.15)
				)
				(justify left bottom)
				(hide yes)
			)
		)
		(property "License" "Apache-2.0"
			(at 107.95 186.69 0)
			(effects
				(font
					(size 1.27 1.27)
					(thickness 0.15)
				)
				(justify left bottom)
				(hide yes)
			)
		)
		(pin "1"
		)
		(instances
			(project "k410t-devboard"
				(path ""
					(reference "#PWR0218")
					(unit 1)
				)
			)
		)
	)
	(symbol
		(lib_id "antmicropower:GND")
		(at 353.06 246.38 0)
		(unit 1)
		(exclude_from_sim no)
		(in_bom yes)
		(on_board yes)
		(dnp no)
		(property "Reference" "#PWR0271"
			(at 353.06 252.73 0)
			(effects
				(font
					(size 1.27 1.27)
				)
				(hide yes)
			)
		)
		(property "Value" "GND"
			(at 353.06 250.19 0)
			(effects
				(font
					(size 1.27 1.27)
				)
			)
		)
		(property "Footprint" ""
			(at 361.95 254 0)
			(effects
				(font
					(size 1.27 1.27)
					(thickness 0.15)
				)
				(justify left bottom)
				(hide yes)
			)
		)
		(property "Datasheet" ""
			(at 361.95 259.08 0)
			(effects
				(font
					(size 1.27 1.27)
					(thickness 0.15)
				)
				(justify left bottom)
				(hide yes)
			)
		)
		(property "Description" ""
			(at 353.06 246.38 0)
			(effects
				(font
					(size 1.27 1.27)
				)
			)
		)
		(property "Author" "Antmicro"
			(at 361.95 254 0)
			(effects
				(font
					(size 1.27 1.27)
					(thickness 0.15)
				)
				(justify left bottom)
				(hide yes)
			)
		)
		(property "License" "Apache-2.0"
			(at 361.95 256.54 0)
			(effects
				(font
					(size 1.27 1.27)
					(thickness 0.15)
				)
				(justify left bottom)
				(hide yes)
			)
		)
		(pin "1"
		)
		(instances
			(project "k410t-devboard"
				(path ""
					(reference "#PWR0271")
					(unit 1)
				)
			)
		)
	)
	(symbol
		(lib_id "antmicroLogicTranslatorsLevelShifters:TXU0304BQAR")
		(at 313.69 172.72 0)
		(unit 1)
		(exclude_from_sim no)
		(in_bom yes)
		(on_board yes)
		(dnp no)
		(fields_autoplaced yes)
		(property "Reference" "U23"
			(at 322.58 165.1 0)
			(effects
				(font
					(size 1.27 1.27)
				)
			)
		)
		(property "Value" "TXU0304BQAR"
			(at 322.58 168.91 0)
			(effects
				(font
					(size 1.27 1.27)
					(thickness 0.15)
				)
				(hide yes)
			)
		)
		(property "Footprint" "antmicro-footprints:DHVQFN-14-1EP_2.5x3mm"
			(at 345.44 177.8 0)
			(effects
				(font
					(size 1.27 1.27)
					(thickness 0.15)
				)
				(justify left bottom)
				(hide yes)
			)
		)
		(property "Datasheet" "https://www.ti.com/lit/ds/symlink/txu0304.pdf?ts=1637748643258&ref_url=https%253A%252F%252Fwww.ti.com%252Fproduct%252FTXU0304"
			(at 345.44 180.34 0)
			(effects
				(font
					(size 1.27 1.27)
					(thickness 0.15)
				)
				(justify left bottom)
				(hide yes)
			)
		)
		(property "Description" ""
			(at 313.69 172.72 0)
			(effects
				(font
					(size 1.27 1.27)
				)
			)
		)
		(property "MPN" "TXU0304BQAR"
			(at 322.58 167.64 0)
			(effects
				(font
					(size 1.27 1.27)
					(thickness 0.15)
				)
			)
		)
		(property "Manufacturer" "Texas Instruments"
			(at 345.44 185.42 0)
			(effects
				(font
					(size 1.27 1.27)
					(thickness 0.15)
				)
				(justify left bottom)
				(hide yes)
			)
		)
		(property "Author" "Antmicro"
			(at 345.44 187.96 0)
			(effects
				(font
					(size 1.27 1.27)
					(thickness 0.15)
				)
				(justify left bottom)
				(hide yes)
			)
		)
		(property "License" "Apache-2.0"
			(at 345.44 190.5 0)
			(effects
				(font
					(size 1.27 1.27)
					(thickness 0.15)
				)
				(justify left bottom)
				(hide yes)
			)
		)
		(pin "1"
		)
		(pin "10"
		)
		(pin "11"
		)
		(pin "12"
		)
		(pin "13"
		)
		(pin "14"
		)
		(pin "15"
		)
		(pin "2"
		)
		(pin "3"
		)
		(pin "4"
		)
		(pin "5"
		)
		(pin "6"
		)
		(pin "7"
		)
		(pin "8"
		)
		(pin "9"
		)
		(instances
			(project "k410t-devboard"
				(path ""
					(reference "U23")
					(unit 1)
				)
			)
		)
	)
	(symbol
		(lib_id "antmicroResistors0402:R_1k5_0402")
		(at 300.99 53.34 0)
		(unit 1)
		(exclude_from_sim no)
		(in_bom no)
		(on_board yes)
		(dnp yes)
		(property "Reference" "R172"
			(at 308.61 52.07 0)
			(effects
				(font
					(size 1.27 1.27)
				)
			)
		)
		(property "Value" "R_1k5_0402"
			(at 321.31 66.04 0)
			(effects
				(font
					(size 1.27 1.27)
					(thickness 0.15)
				)
				(justify left bottom)
				(hide yes)
			)
		)
		(property "Footprint" "antmicro-footprints:R_0402_1005Metric"
			(at 321.31 68.58 0)
			(effects
				(font
					(size 1.27 1.27)
					(thickness 0.15)
				)
				(justify left bottom)
				(hide yes)
			)
		)
		(property "Datasheet" "https://www.bourns.com/docs/product-datasheets/cr.pdf"
			(at 321.31 71.12 0)
			(effects
				(font
					(size 1.27 1.27)
					(thickness 0.15)
				)
				(justify left bottom)
				(hide yes)
			)
		)
		(property "Description" ""
			(at 300.99 53.34 0)
			(effects
				(font
					(size 1.27 1.27)
				)
			)
		)
		(property "Manufacturer" "Bourns"
			(at 321.31 76.2 0)
			(effects
				(font
					(size 1.27 1.27)
					(thickness 0.15)
				)
				(justify left bottom)
				(hide yes)
			)
		)
		(property "MPN" "CR0402-FX-1501GLF"
			(at 321.31 73.66 0)
			(effects
				(font
					(size 1.27 1.27)
					(thickness 0.15)
				)
				(justify left bottom)
				(hide yes)
			)
		)
		(property "Val" "1k5"
			(at 299.085 52.07 0)
			(effects
				(font
					(size 1.27 1.27)
					(thickness 0.15)
				)
			)
		)
		(property "DNP" "DNP"
			(at 303.53 53.34 0)
			(effects
				(font
					(size 1.27 1.27)
				)
			)
		)
		(property "License" "Apache-2.0"
			(at 321.31 78.74 0)
			(effects
				(font
					(size 1.27 1.27)
					(thickness 0.15)
				)
				(justify left bottom)
				(hide yes)
			)
		)
		(property "Author" "Antmicro"
			(at 321.31 81.28 0)
			(effects
				(font
					(size 1.27 1.27)
					(thickness 0.15)
				)
				(justify left bottom)
				(hide yes)
			)
		)
		(property "Tolerance" "1%"
			(at 321.31 63.5 0)
			(effects
				(font
					(size 1.27 1.27)
				)
				(justify left bottom)
				(hide yes)
			)
		)
		(pin "1"
		)
		(pin "2"
		)
		(instances
			(project "k410t-devboard"
				(path ""
					(reference "R172")
					(unit 1)
				)
			)
		)
	)
	(symbol
		(lib_id "antmicroResistors0402:R_10k_0402")
		(at 121.92 55.88 180)
		(unit 1)
		(exclude_from_sim no)
		(in_bom yes)
		(on_board yes)
		(dnp no)
		(property "Reference" "R157"
			(at 124.46 54.61 0)
			(effects
				(font
					(size 1.27 1.27)
				)
			)
		)
		(property "Value" "R_10k_0402"
			(at 101.6 43.18 0)
			(effects
				(font
					(size 1.27 1.27)
					(thickness 0.15)
				)
				(justify left bottom)
				(hide yes)
			)
		)
		(property "Footprint" "antmicro-footprints:R_0402_1005Metric"
			(at 101.6 40.64 0)
			(effects
				(font
					(size 1.27 1.27)
					(thickness 0.15)
				)
				(justify left bottom)
				(hide yes)
			)
		)
		(property "Datasheet" "https://www.bourns.com/docs/product-datasheets/cr.pdf"
			(at 101.6 38.1 0)
			(effects
				(font
					(size 1.27 1.27)
					(thickness 0.15)
				)
				(justify left bottom)
				(hide yes)
			)
		)
		(property "Description" ""
			(at 121.92 55.88 0)
			(effects
				(font
					(size 1.27 1.27)
				)
			)
		)
		(property "Manufacturer" "Bourns"
			(at 101.6 33.02 0)
			(effects
				(font
					(size 1.27 1.27)
					(thickness 0.15)
				)
				(justify left bottom)
				(hide yes)
			)
		)
		(property "MPN" "CR0402-FX-1002GLF"
			(at 101.6 35.56 0)
			(effects
				(font
					(size 1.27 1.27)
					(thickness 0.15)
				)
				(justify left bottom)
				(hide yes)
			)
		)
		(property "Val" "10k"
			(at 114.935 54.61 0)
			(effects
				(font
					(size 1.27 1.27)
					(thickness 0.15)
				)
			)
		)
		(property "License" "Apache-2.0"
			(at 101.6 30.48 0)
			(effects
				(font
					(size 1.27 1.27)
					(thickness 0.15)
				)
				(justify left bottom)
				(hide yes)
			)
		)
		(property "Author" "Antmicro"
			(at 101.6 27.94 0)
			(effects
				(font
					(size 1.27 1.27)
					(thickness 0.15)
				)
				(justify left bottom)
				(hide yes)
			)
		)
		(property "Tolerance" "1%"
			(at 101.6 45.72 0)
			(effects
				(font
					(size 1.27 1.27)
				)
				(justify left bottom)
				(hide yes)
			)
		)
		(pin "1"
		)
		(pin "2"
		)
		(instances
			(project "k410t-devboard"
				(path ""
					(reference "R157")
					(unit 1)
				)
			)
		)
	)
	(symbol
		(lib_id "antmicropower:GND")
		(at 115.57 153.67 0)
		(unit 1)
		(exclude_from_sim no)
		(in_bom yes)
		(on_board yes)
		(dnp no)
		(property "Reference" "#PWR0216"
			(at 115.57 160.02 0)
			(effects
				(font
					(size 1.27 1.27)
				)
				(hide yes)
			)
		)
		(property "Value" "GND"
			(at 115.57 157.48 0)
			(effects
				(font
					(size 1.27 1.27)
				)
			)
		)
		(property "Footprint" ""
			(at 124.46 161.29 0)
			(effects
				(font
					(size 1.27 1.27)
					(thickness 0.15)
				)
				(justify left bottom)
				(hide yes)
			)
		)
		(property "Datasheet" ""
			(at 124.46 166.37 0)
			(effects
				(font
					(size 1.27 1.27)
					(thickness 0.15)
				)
				(justify left bottom)
				(hide yes)
			)
		)
		(property "Description" ""
			(at 115.57 153.67 0)
			(effects
				(font
					(size 1.27 1.27)
				)
			)
		)
		(property "Author" "Antmicro"
			(at 124.46 161.29 0)
			(effects
				(font
					(size 1.27 1.27)
					(thickness 0.15)
				)
				(justify left bottom)
				(hide yes)
			)
		)
		(property "License" "Apache-2.0"
			(at 124.46 163.83 0)
			(effects
				(font
					(size 1.27 1.27)
					(thickness 0.15)
				)
				(justify left bottom)
				(hide yes)
			)
		)
		(pin "1"
		)
		(instances
			(project "k410t-devboard"
				(path ""
					(reference "#PWR0216")
					(unit 1)
				)
			)
		)
	)
	(symbol
		(lib_id "antmicroResistors0402:R_330R_0402")
		(at 80.01 252.73 0)
		(unit 1)
		(exclude_from_sim no)
		(in_bom yes)
		(on_board yes)
		(dnp no)
		(property "Reference" "R153"
			(at 85.09 252.73 0)
			(effects
				(font
					(size 1.524 1.524)
				)
				(justify left bottom)
			)
		)
		(property "Value" "R_330R_0402"
			(at 100.33 265.43 0)
			(effects
				(font
					(size 1.27 1.27)
					(thickness 0.15)
				)
				(justify left bottom)
				(hide yes)
			)
		)
		(property "Footprint" "antmicro-footprints:R_0402_1005Metric"
			(at 100.33 267.97 0)
			(effects
				(font
					(size 1.27 1.27)
					(thickness 0.15)
				)
				(justify left bottom)
				(hide yes)
			)
		)
		(property "Datasheet" "https://www.bourns.com/docs/product-datasheets/cr.pdf"
			(at 100.33 270.51 0)
			(effects
				(font
					(size 1.27 1.27)
					(thickness 0.15)
				)
				(justify left bottom)
				(hide yes)
			)
		)
		(property "Description" ""
			(at 80.01 252.73 0)
			(effects
				(font
					(size 1.27 1.27)
				)
			)
		)
		(property "Manufacturer" "Bourns"
			(at 100.33 275.59 0)
			(effects
				(font
					(size 1.27 1.27)
					(thickness 0.15)
				)
				(justify left bottom)
				(hide yes)
			)
		)
		(property "MPN" "CR0402-FX-3300GLF"
			(at 100.33 273.05 0)
			(effects
				(font
					(size 1.27 1.27)
					(thickness 0.15)
				)
				(justify left bottom)
				(hide yes)
			)
		)
		(property "Val" "330R"
			(at 74.93 252.73 0)
			(effects
				(font
					(size 1.27 1.27)
					(thickness 0.15)
				)
				(justify left bottom)
			)
		)
		(property "License" "Apache-2.0"
			(at 100.33 278.13 0)
			(effects
				(font
					(size 1.27 1.27)
					(thickness 0.15)
				)
				(justify left bottom)
				(hide yes)
			)
		)
		(property "Author" "Antmicro"
			(at 100.33 280.67 0)
			(effects
				(font
					(size 1.27 1.27)
					(thickness 0.15)
				)
				(justify left bottom)
				(hide yes)
			)
		)
		(property "Tolerance" "1%"
			(at 100.33 262.89 0)
			(effects
				(font
					(size 1.27 1.27)
				)
				(justify left bottom)
				(hide yes)
			)
		)
		(pin "1"
		)
		(pin "2"
		)
		(instances
			(project "k410t-devboard"
				(path ""
					(reference "R153")
					(unit 1)
				)
			)
		)
	)
	(symbol
		(lib_id "antmicroLogicTranslatorsLevelShifters:TXU0304BQAR")
		(at 313.69 205.74 0)
		(unit 1)
		(exclude_from_sim no)
		(in_bom yes)
		(on_board yes)
		(dnp no)
		(fields_autoplaced yes)
		(property "Reference" "U24"
			(at 322.58 198.12 0)
			(effects
				(font
					(size 1.27 1.27)
				)
			)
		)
		(property "Value" "TXU0304BQAR"
			(at 322.58 201.93 0)
			(effects
				(font
					(size 1.27 1.27)
					(thickness 0.15)
				)
				(hide yes)
			)
		)
		(property "Footprint" "antmicro-footprints:DHVQFN-14-1EP_2.5x3mm"
			(at 345.44 210.82 0)
			(effects
				(font
					(size 1.27 1.27)
					(thickness 0.15)
				)
				(justify left bottom)
				(hide yes)
			)
		)
		(property "Datasheet" "https://www.ti.com/lit/ds/symlink/txu0304.pdf?ts=1637748643258&ref_url=https%253A%252F%252Fwww.ti.com%252Fproduct%252FTXU0304"
			(at 345.44 213.36 0)
			(effects
				(font
					(size 1.27 1.27)
					(thickness 0.15)
				)
				(justify left bottom)
				(hide yes)
			)
		)
		(property "Description" ""
			(at 313.69 205.74 0)
			(effects
				(font
					(size 1.27 1.27)
				)
			)
		)
		(property "MPN" "TXU0304BQAR"
			(at 322.58 200.66 0)
			(effects
				(font
					(size 1.27 1.27)
					(thickness 0.15)
				)
			)
		)
		(property "Manufacturer" "Texas Instruments"
			(at 345.44 218.44 0)
			(effects
				(font
					(size 1.27 1.27)
					(thickness 0.15)
				)
				(justify left bottom)
				(hide yes)
			)
		)
		(property "Author" "Antmicro"
			(at 345.44 220.98 0)
			(effects
				(font
					(size 1.27 1.27)
					(thickness 0.15)
				)
				(justify left bottom)
				(hide yes)
			)
		)
		(property "License" "Apache-2.0"
			(at 345.44 223.52 0)
			(effects
				(font
					(size 1.27 1.27)
					(thickness 0.15)
				)
				(justify left bottom)
				(hide yes)
			)
		)
		(pin "1"
		)
		(pin "10"
		)
		(pin "11"
		)
		(pin "12"
		)
		(pin "13"
		)
		(pin "14"
		)
		(pin "15"
		)
		(pin "2"
		)
		(pin "3"
		)
		(pin "4"
		)
		(pin "5"
		)
		(pin "6"
		)
		(pin "7"
		)
		(pin "8"
		)
		(pin "9"
		)
		(instances
			(project "k410t-devboard"
				(path ""
					(reference "U24")
					(unit 1)
				)
			)
		)
	)
	(symbol
		(lib_id "antmicroUSBConnectors:USB-A_WE_614004184726")
		(at 50.8 34.29 0)
		(unit 1)
		(exclude_from_sim no)
		(in_bom yes)
		(on_board yes)
		(dnp no)
		(property "Reference" "J12"
			(at 43.18 27.94 0)
			(effects
				(font
					(size 1.27 1.27)
				)
			)
		)
		(property "Value" "USB-A_WE_614004184726"
			(at 43.18 30.48 0)
			(effects
				(font
					(size 1.27 1.27)
					(thickness 0.15)
				)
			)
		)
		(property "Footprint" "antmicro-footprints:USB-A_Receptacle_WE_614004184726"
			(at 66.04 44.45 0)
			(effects
				(font
					(size 1.27 1.27)
					(thickness 0.15)
				)
				(justify left bottom)
				(hide yes)
			)
		)
		(property "Datasheet" "https://www.we-online.com/katalog/datasheet/614004184726.pdf"
			(at 66.04 46.99 0)
			(effects
				(font
					(size 1.27 1.27)
					(thickness 0.15)
				)
				(justify left bottom)
				(hide yes)
			)
		)
		(property "Description" ""
			(at 50.8 34.29 0)
			(effects
				(font
					(size 1.27 1.27)
				)
			)
		)
		(property "MPN" "614004184726"
			(at 66.04 49.53 0)
			(effects
				(font
					(size 1.27 1.27)
					(thickness 0.15)
				)
				(justify left bottom)
				(hide yes)
			)
		)
		(property "Manufacturer" "Würth Elektronik"
			(at 66.04 52.07 0)
			(effects
				(font
					(size 1.27 1.27)
					(thickness 0.15)
				)
				(justify left bottom)
				(hide yes)
			)
		)
		(property "Author" "Antmicro"
			(at 66.04 54.61 0)
			(effects
				(font
					(size 1.27 1.27)
					(thickness 0.15)
				)
				(justify left bottom)
				(hide yes)
			)
		)
		(property "License" "Apache-2.0"
			(at 66.04 57.15 0)
			(effects
				(font
					(size 1.27 1.27)
					(thickness 0.15)
				)
				(justify left bottom)
				(hide yes)
			)
		)
		(pin "1"
		)
		(pin "2"
		)
		(pin "3"
		)
		(pin "4"
		)
		(pin "SH"
		)
		(instances
			(project "k410t-devboard"
				(path ""
					(reference "J12")
					(unit 1)
				)
			)
		)
	)
	(symbol
		(lib_id "antmicroResistors0402:R_33R_0402")
		(at 341.63 143.51 0)
		(unit 1)
		(exclude_from_sim no)
		(in_bom yes)
		(on_board yes)
		(dnp no)
		(property "Reference" "R176"
			(at 349.25 142.24 0)
			(effects
				(font
					(size 1.27 1.27)
				)
			)
		)
		(property "Value" "R_33R_0402"
			(at 361.95 156.21 0)
			(effects
				(font
					(size 1.27 1.27)
					(thickness 0.15)
				)
				(justify left bottom)
				(hide yes)
			)
		)
		(property "Footprint" "antmicro-footprints:R_0402_1005Metric"
			(at 361.95 158.75 0)
			(effects
				(font
					(size 1.27 1.27)
					(thickness 0.15)
				)
				(justify left bottom)
				(hide yes)
			)
		)
		(property "Datasheet" "https://www.bourns.com/docs/product-datasheets/cr.pdf"
			(at 361.95 161.29 0)
			(effects
				(font
					(size 1.27 1.27)
					(thickness 0.15)
				)
				(justify left bottom)
				(hide yes)
			)
		)
		(property "Description" ""
			(at 341.63 143.51 0)
			(effects
				(font
					(size 1.27 1.27)
				)
			)
		)
		(property "Manufacturer" "Bourns"
			(at 361.95 166.37 0)
			(effects
				(font
					(size 1.27 1.27)
					(thickness 0.15)
				)
				(justify left bottom)
				(hide yes)
			)
		)
		(property "MPN" "CR0402-FX-33R0GLF"
			(at 361.95 163.83 0)
			(effects
				(font
					(size 1.27 1.27)
					(thickness 0.15)
				)
				(justify left bottom)
				(hide yes)
			)
		)
		(property "Val" "33R"
			(at 339.725 142.24 0)
			(effects
				(font
					(size 1.27 1.27)
					(thickness 0.15)
				)
			)
		)
		(property "License" "Apache-2.0"
			(at 361.95 168.91 0)
			(effects
				(font
					(size 1.27 1.27)
					(thickness 0.15)
				)
				(justify left bottom)
				(hide yes)
			)
		)
		(property "Author" "Antmicro"
			(at 361.95 171.45 0)
			(effects
				(font
					(size 1.27 1.27)
					(thickness 0.15)
				)
				(justify left bottom)
				(hide yes)
			)
		)
		(property "Tolerance" "1%"
			(at 361.95 153.67 0)
			(effects
				(font
					(size 1.27 1.27)
				)
				(justify left bottom)
				(hide yes)
			)
		)
		(pin "1"
		)
		(pin "2"
		)
		(instances
			(project "k410t-devboard"
				(path ""
					(reference "R176")
					(unit 1)
				)
			)
		)
	)
	(symbol
		(lib_id "antmicroResistors0402:R_33R_0402")
		(at 341.63 148.59 0)
		(unit 1)
		(exclude_from_sim no)
		(in_bom yes)
		(on_board yes)
		(dnp no)
		(property "Reference" "R178"
			(at 349.25 147.32 0)
			(effects
				(font
					(size 1.27 1.27)
				)
			)
		)
		(property "Value" "R_33R_0402"
			(at 361.95 161.29 0)
			(effects
				(font
					(size 1.27 1.27)
					(thickness 0.15)
				)
				(justify left bottom)
				(hide yes)
			)
		)
		(property "Footprint" "antmicro-footprints:R_0402_1005Metric"
			(at 361.95 163.83 0)
			(effects
				(font
					(size 1.27 1.27)
					(thickness 0.15)
				)
				(justify left bottom)
				(hide yes)
			)
		)
		(property "Datasheet" "https://www.bourns.com/docs/product-datasheets/cr.pdf"
			(at 361.95 166.37 0)
			(effects
				(font
					(size 1.27 1.27)
					(thickness 0.15)
				)
				(justify left bottom)
				(hide yes)
			)
		)
		(property "Description" ""
			(at 341.63 148.59 0)
			(effects
				(font
					(size 1.27 1.27)
				)
			)
		)
		(property "Manufacturer" "Bourns"
			(at 361.95 171.45 0)
			(effects
				(font
					(size 1.27 1.27)
					(thickness 0.15)
				)
				(justify left bottom)
				(hide yes)
			)
		)
		(property "MPN" "CR0402-FX-33R0GLF"
			(at 361.95 168.91 0)
			(effects
				(font
					(size 1.27 1.27)
					(thickness 0.15)
				)
				(justify left bottom)
				(hide yes)
			)
		)
		(property "Val" "33R"
			(at 339.725 147.32 0)
			(effects
				(font
					(size 1.27 1.27)
					(thickness 0.15)
				)
			)
		)
		(property "License" "Apache-2.0"
			(at 361.95 173.99 0)
			(effects
				(font
					(size 1.27 1.27)
					(thickness 0.15)
				)
				(justify left bottom)
				(hide yes)
			)
		)
		(property "Author" "Antmicro"
			(at 361.95 176.53 0)
			(effects
				(font
					(size 1.27 1.27)
					(thickness 0.15)
				)
				(justify left bottom)
				(hide yes)
			)
		)
		(property "Tolerance" "1%"
			(at 361.95 158.75 0)
			(effects
				(font
					(size 1.27 1.27)
				)
				(justify left bottom)
				(hide yes)
			)
		)
		(pin "1"
		)
		(pin "2"
		)
		(instances
			(project "k410t-devboard"
				(path ""
					(reference "R178")
					(unit 1)
				)
			)
		)
	)
	(symbol
		(lib_id "antmicroFerriteBeadsandChips:FB_600Z_0.5A_Murata-BLM18AG_0603")
		(at 146.05 125.73 0)
		(unit 1)
		(exclude_from_sim no)
		(in_bom yes)
		(on_board yes)
		(dnp no)
		(fields_autoplaced yes)
		(property "Reference" "FB5"
			(at 148.5519 119.38 0)
			(effects
				(font
					(size 1.27 1.27)
				)
			)
		)
		(property "Value" "FB_600Z_0.5A_Murata-BLM18AG_0603"
			(at 148.5519 121.92 0)
			(effects
				(font
					(size 1.27 1.27)
					(thickness 0.15)
				)
				(hide yes)
			)
		)
		(property "Footprint" "antmicro-footprints:FB_0603_1608Metric"
			(at 160.02 130.81 0)
			(effects
				(font
					(size 1.27 1.27)
					(thickness 0.15)
				)
				(justify left bottom)
				(hide yes)
			)
		)
		(property "Datasheet" "https://www.murata.com/en-us/products/productdata/8796738650142/ENFA0003.pdf"
			(at 160.02 133.35 0)
			(effects
				(font
					(size 1.27 1.27)
					(thickness 0.15)
				)
				(justify left bottom)
				(hide yes)
			)
		)
		(property "Description" ""
			(at 146.05 125.73 0)
			(effects
				(font
					(size 1.27 1.27)
				)
			)
		)
		(property "MPN" "BLM18AG601SN1D"
			(at 160.02 135.89 0)
			(effects
				(font
					(size 1.27 1.27)
					(thickness 0.15)
				)
				(justify left bottom)
				(hide yes)
			)
		)
		(property "Manufacturer" "Murata"
			(at 160.02 138.43 0)
			(effects
				(font
					(size 1.27 1.27)
					(thickness 0.15)
				)
				(justify left bottom)
				(hide yes)
			)
		)
		(property "Author" "Antmicro"
			(at 160.02 140.97 0)
			(effects
				(font
					(size 1.27 1.27)
					(thickness 0.15)
				)
				(justify left bottom)
				(hide yes)
			)
		)
		(property "License" "Apache-2.0"
			(at 160.02 143.51 0)
			(effects
				(font
					(size 1.27 1.27)
					(thickness 0.15)
				)
				(justify left bottom)
				(hide yes)
			)
		)
		(property "Val" "600Z/0.5A"
			(at 148.5519 121.92 0)
			(effects
				(font
					(size 1.27 1.27)
				)
			)
		)
		(property "Current" ""
			(at 166.37 148.59 0)
			(effects
				(font
					(size 1.27 1.27)
					(thickness 0.15)
				)
				(justify left bottom)
				(hide yes)
			)
		)
		(pin "1"
		)
		(pin "2"
		)
		(instances
			(project "k410t-devboard"
				(path ""
					(reference "FB5")
					(unit 1)
				)
			)
		)
	)
	(symbol
		(lib_id "antmicroCapacitors0402:C_100n_0402")
		(at 46.99 76.2 90)
		(unit 1)
		(exclude_from_sim no)
		(in_bom yes)
		(on_board yes)
		(dnp no)
		(property "Reference" "C242"
			(at 47.625 71.755 90)
			(effects
				(font
					(size 1.27 1.27)
				)
				(justify right)
			)
		)
		(property "Value" "C_100n_0402"
			(at 57.15 55.88 0)
			(effects
				(font
					(size 1.27 1.27)
					(thickness 0.15)
				)
				(justify left bottom)
				(hide yes)
			)
		)
		(property "Footprint" "antmicro-footprints:C_0402_1005Metric"
			(at 59.69 55.88 0)
			(effects
				(font
					(size 1.27 1.27)
					(thickness 0.15)
				)
				(justify left bottom)
				(hide yes)
			)
		)
		(property "Datasheet" "https://www.murata.com/products/productdetail?partno=GRM155R61H104KE14%23"
			(at 62.23 55.88 0)
			(effects
				(font
					(size 1.27 1.27)
					(thickness 0.15)
				)
				(justify left bottom)
				(hide yes)
			)
		)
		(property "Description" ""
			(at 46.99 76.2 0)
			(effects
				(font
					(size 1.27 1.27)
				)
			)
		)
		(property "Manufacturer" "Murata"
			(at 67.31 55.88 0)
			(effects
				(font
					(size 1.27 1.27)
					(thickness 0.15)
				)
				(justify left bottom)
				(hide yes)
			)
		)
		(property "MPN" "GRM155R61H104KE14D"
			(at 64.77 55.88 0)
			(effects
				(font
					(size 1.27 1.27)
					(thickness 0.15)
				)
				(justify left bottom)
				(hide yes)
			)
		)
		(property "Val" "100n"
			(at 47.625 75.565 90)
			(effects
				(font
					(size 1.27 1.27)
					(thickness 0.15)
				)
				(justify right)
			)
		)
		(property "License" "Apache-2.0"
			(at 69.85 55.88 0)
			(effects
				(font
					(size 1.27 1.27)
					(thickness 0.15)
				)
				(justify left bottom)
				(hide yes)
			)
		)
		(property "Author" "Antmicro"
			(at 72.39 55.88 0)
			(effects
				(font
					(size 1.27 1.27)
					(thickness 0.15)
				)
				(justify left bottom)
				(hide yes)
			)
		)
		(property "Voltage" "50V"
			(at 74.93 55.88 0)
			(effects
				(font
					(size 1.27 1.27)
				)
				(justify left bottom)
				(hide yes)
			)
		)
		(property "Dielectric" "X5R"
			(at 77.47 55.88 0)
			(effects
				(font
					(size 1.27 1.27)
				)
				(justify left bottom)
				(hide yes)
			)
		)
		(pin "1"
		)
		(pin "2"
		)
		(instances
			(project "k410t-devboard"
				(path ""
					(reference "C242")
					(unit 1)
				)
			)
		)
	)
	(symbol
		(lib_id "antmicroCapacitors0402:C_100n_0402")
		(at 392.43 96.52 90)
		(unit 1)
		(exclude_from_sim no)
		(in_bom yes)
		(on_board yes)
		(dnp no)
		(property "Reference" "C396"
			(at 393.065 92.075 90)
			(effects
				(font
					(size 1.27 1.27)
				)
				(justify right)
			)
		)
		(property "Value" "C_100n_0402"
			(at 402.59 76.2 0)
			(effects
				(font
					(size 1.27 1.27)
					(thickness 0.15)
				)
				(justify left bottom)
				(hide yes)
			)
		)
		(property "Footprint" "antmicro-footprints:C_0402_1005Metric"
			(at 405.13 76.2 0)
			(effects
				(font
					(size 1.27 1.27)
					(thickness 0.15)
				)
				(justify left bottom)
				(hide yes)
			)
		)
		(property "Datasheet" "https://www.murata.com/products/productdetail?partno=GRM155R61H104KE14%23"
			(at 407.67 76.2 0)
			(effects
				(font
					(size 1.27 1.27)
					(thickness 0.15)
				)
				(justify left bottom)
				(hide yes)
			)
		)
		(property "Description" ""
			(at 392.43 96.52 0)
			(effects
				(font
					(size 1.27 1.27)
				)
			)
		)
		(property "Manufacturer" "Murata"
			(at 412.75 76.2 0)
			(effects
				(font
					(size 1.27 1.27)
					(thickness 0.15)
				)
				(justify left bottom)
				(hide yes)
			)
		)
		(property "MPN" "GRM155R61H104KE14D"
			(at 410.21 76.2 0)
			(effects
				(font
					(size 1.27 1.27)
					(thickness 0.15)
				)
				(justify left bottom)
				(hide yes)
			)
		)
		(property "Val" "100n"
			(at 393.065 95.885 90)
			(effects
				(font
					(size 1.27 1.27)
					(thickness 0.15)
				)
				(justify right)
			)
		)
		(property "License" "Apache-2.0"
			(at 415.29 76.2 0)
			(effects
				(font
					(size 1.27 1.27)
					(thickness 0.15)
				)
				(justify left bottom)
				(hide yes)
			)
		)
		(property "Author" "Antmicro"
			(at 417.83 76.2 0)
			(effects
				(font
					(size 1.27 1.27)
					(thickness 0.15)
				)
				(justify left bottom)
				(hide yes)
			)
		)
		(property "Voltage" "50V"
			(at 420.37 76.2 0)
			(effects
				(font
					(size 1.27 1.27)
				)
				(justify left bottom)
				(hide yes)
			)
		)
		(property "Dielectric" "X5R"
			(at 422.91 76.2 0)
			(effects
				(font
					(size 1.27 1.27)
				)
				(justify left bottom)
				(hide yes)
			)
		)
		(pin "1"
		)
		(pin "2"
		)
		(instances
			(project "k410t-devboard"
				(path ""
					(reference "C396")
					(unit 1)
				)
			)
		)
	)
	(symbol
		(lib_id "antmicropower:+3.3V")
		(at 334.01 201.93 0)
		(unit 1)
		(exclude_from_sim no)
		(in_bom yes)
		(on_board yes)
		(dnp no)
		(property "Reference" "#PWR0237"
			(at 334.01 205.74 0)
			(effects
				(font
					(size 1.27 1.27)
				)
				(hide yes)
			)
		)
		(property "Value" "+3V3"
			(at 334.01 198.374 0)
			(effects
				(font
					(size 1.27 1.27)
				)
			)
		)
		(property "Footprint" ""
			(at 334.01 201.93 0)
			(effects
				(font
					(size 1.27 1.27)
				)
				(hide yes)
			)
		)
		(property "Datasheet" ""
			(at 334.01 201.93 0)
			(effects
				(font
					(size 1.27 1.27)
				)
				(hide yes)
			)
		)
		(property "Description" ""
			(at 334.01 201.93 0)
			(effects
				(font
					(size 1.27 1.27)
				)
			)
		)
		(pin "1"
		)
		(instances
			(project "k410t-devboard"
				(path ""
					(reference "#PWR0237")
					(unit 1)
				)
			)
		)
	)
	(symbol
		(lib_id "antmicroResistors0402:R_10k_0402")
		(at 57.15 91.44 270)
		(unit 1)
		(exclude_from_sim no)
		(in_bom yes)
		(on_board yes)
		(dnp no)
		(property "Reference" "R345"
			(at 58.42 92.71 90)
			(effects
				(font
					(size 1.27 1.27)
				)
				(justify left)
			)
		)
		(property "Value" "R_10k_0402"
			(at 44.45 111.76 0)
			(effects
				(font
					(size 1.27 1.27)
					(thickness 0.15)
				)
				(justify left bottom)
				(hide yes)
			)
		)
		(property "Footprint" "antmicro-footprints:R_0402_1005Metric"
			(at 41.91 111.76 0)
			(effects
				(font
					(size 1.27 1.27)
					(thickness 0.15)
				)
				(justify left bottom)
				(hide yes)
			)
		)
		(property "Datasheet" "https://www.bourns.com/docs/product-datasheets/cr.pdf"
			(at 39.37 111.76 0)
			(effects
				(font
					(size 1.27 1.27)
					(thickness 0.15)
				)
				(justify left bottom)
				(hide yes)
			)
		)
		(property "Description" ""
			(at 57.15 91.44 0)
			(effects
				(font
					(size 1.27 1.27)
				)
			)
		)
		(property "Manufacturer" "Bourns"
			(at 34.29 111.76 0)
			(effects
				(font
					(size 1.27 1.27)
					(thickness 0.15)
				)
				(justify left bottom)
				(hide yes)
			)
		)
		(property "MPN" "CR0402-FX-1002GLF"
			(at 36.83 111.76 0)
			(effects
				(font
					(size 1.27 1.27)
					(thickness 0.15)
				)
				(justify left bottom)
				(hide yes)
			)
		)
		(property "Val" "10k"
			(at 58.42 95.25 90)
			(effects
				(font
					(size 1.27 1.27)
					(thickness 0.15)
				)
				(justify left)
			)
		)
		(property "License" "Apache-2.0"
			(at 31.75 111.76 0)
			(effects
				(font
					(size 1.27 1.27)
					(thickness 0.15)
				)
				(justify left bottom)
				(hide yes)
			)
		)
		(property "Author" "Antmicro"
			(at 29.21 111.76 0)
			(effects
				(font
					(size 1.27 1.27)
					(thickness 0.15)
				)
				(justify left bottom)
				(hide yes)
			)
		)
		(property "Tolerance" "1%"
			(at 46.99 111.76 0)
			(effects
				(font
					(size 1.27 1.27)
				)
				(justify left bottom)
				(hide yes)
			)
		)
		(pin "1"
		)
		(pin "2"
		)
		(instances
			(project "k410t-devboard"
				(path ""
					(reference "R345")
					(unit 1)
				)
			)
		)
	)
	(symbol
		(lib_id "antmicroResistors0402:R_10k_0402")
		(at 121.92 53.34 180)
		(unit 1)
		(exclude_from_sim no)
		(in_bom yes)
		(on_board yes)
		(dnp no)
		(property "Reference" "R156"
			(at 124.46 52.07 0)
			(effects
				(font
					(size 1.27 1.27)
				)
			)
		)
		(property "Value" "R_10k_0402"
			(at 101.6 40.64 0)
			(effects
				(font
					(size 1.27 1.27)
					(thickness 0.15)
				)
				(justify left bottom)
				(hide yes)
			)
		)
		(property "Footprint" "antmicro-footprints:R_0402_1005Metric"
			(at 101.6 38.1 0)
			(effects
				(font
					(size 1.27 1.27)
					(thickness 0.15)
				)
				(justify left bottom)
				(hide yes)
			)
		)
		(property "Datasheet" "https://www.bourns.com/docs/product-datasheets/cr.pdf"
			(at 101.6 35.56 0)
			(effects
				(font
					(size 1.27 1.27)
					(thickness 0.15)
				)
				(justify left bottom)
				(hide yes)
			)
		)
		(property "Description" ""
			(at 121.92 53.34 0)
			(effects
				(font
					(size 1.27 1.27)
				)
			)
		)
		(property "Manufacturer" "Bourns"
			(at 101.6 30.48 0)
			(effects
				(font
					(size 1.27 1.27)
					(thickness 0.15)
				)
				(justify left bottom)
				(hide yes)
			)
		)
		(property "MPN" "CR0402-FX-1002GLF"
			(at 101.6 33.02 0)
			(effects
				(font
					(size 1.27 1.27)
					(thickness 0.15)
				)
				(justify left bottom)
				(hide yes)
			)
		)
		(property "Val" "10k"
			(at 114.935 52.07 0)
			(effects
				(font
					(size 1.27 1.27)
					(thickness 0.15)
				)
			)
		)
		(property "License" "Apache-2.0"
			(at 101.6 27.94 0)
			(effects
				(font
					(size 1.27 1.27)
					(thickness 0.15)
				)
				(justify left bottom)
				(hide yes)
			)
		)
		(property "Author" "Antmicro"
			(at 101.6 25.4 0)
			(effects
				(font
					(size 1.27 1.27)
					(thickness 0.15)
				)
				(justify left bottom)
				(hide yes)
			)
		)
		(property "Tolerance" "1%"
			(at 101.6 43.18 0)
			(effects
				(font
					(size 1.27 1.27)
				)
				(justify left bottom)
				(hide yes)
			)
		)
		(pin "1"
		)
		(pin "2"
		)
		(instances
			(project "k410t-devboard"
				(path ""
					(reference "R156")
					(unit 1)
				)
			)
		)
	)
	(symbol
		(lib_id "antmicroResistors0402:R_2k2_0402")
		(at 382.27 91.44 270)
		(unit 1)
		(exclude_from_sim no)
		(in_bom yes)
		(on_board yes)
		(dnp no)
		(property "Reference" "R351"
			(at 383.54 92.71 90)
			(effects
				(font
					(size 1.27 1.27)
				)
				(justify left)
			)
		)
		(property "Value" "R_2k2_0402"
			(at 369.57 111.76 0)
			(effects
				(font
					(size 1.27 1.27)
					(thickness 0.15)
				)
				(justify left bottom)
				(hide yes)
			)
		)
		(property "Footprint" "antmicro-footprints:R_0402_1005Metric"
			(at 367.03 111.76 0)
			(effects
				(font
					(size 1.27 1.27)
					(thickness 0.15)
				)
				(justify left bottom)
				(hide yes)
			)
		)
		(property "Datasheet" "https://www.bourns.com/docs/product-datasheets/cr.pdf"
			(at 364.49 111.76 0)
			(effects
				(font
					(size 1.27 1.27)
					(thickness 0.15)
				)
				(justify left bottom)
				(hide yes)
			)
		)
		(property "Description" ""
			(at 382.27 91.44 0)
			(effects
				(font
					(size 1.27 1.27)
				)
			)
		)
		(property "Manufacturer" "Bourns"
			(at 359.41 111.76 0)
			(effects
				(font
					(size 1.27 1.27)
					(thickness 0.15)
				)
				(justify left bottom)
				(hide yes)
			)
		)
		(property "MPN" "CR0402-FX-2201GLF"
			(at 361.95 111.76 0)
			(effects
				(font
					(size 1.27 1.27)
					(thickness 0.15)
				)
				(justify left bottom)
				(hide yes)
			)
		)
		(property "Val" "2k2"
			(at 383.54 95.25 90)
			(effects
				(font
					(size 1.27 1.27)
					(thickness 0.15)
				)
				(justify left)
			)
		)
		(property "License" "Apache-2.0"
			(at 356.87 111.76 0)
			(effects
				(font
					(size 1.27 1.27)
					(thickness 0.15)
				)
				(justify left bottom)
				(hide yes)
			)
		)
		(property "Author" "Antmicro"
			(at 354.33 111.76 0)
			(effects
				(font
					(size 1.27 1.27)
					(thickness 0.15)
				)
				(justify left bottom)
				(hide yes)
			)
		)
		(property "Tolerance" "1%"
			(at 372.11 111.76 0)
			(effects
				(font
					(size 1.27 1.27)
				)
				(justify left bottom)
				(hide yes)
			)
		)
		(pin "1"
		)
		(pin "2"
		)
		(instances
			(project "k410t-devboard"
				(path ""
					(reference "R351")
					(unit 1)
				)
			)
		)
	)
	(symbol
		(lib_id "antmicroCapacitors0402:C_100n_0402")
		(at 353.06 245.11 90)
		(unit 1)
		(exclude_from_sim no)
		(in_bom yes)
		(on_board yes)
		(dnp no)
		(property "Reference" "C248"
			(at 353.695 240.665 90)
			(effects
				(font
					(size 1.27 1.27)
				)
				(justify right)
			)
		)
		(property "Value" "C_100n_0402"
			(at 363.22 224.79 0)
			(effects
				(font
					(size 1.27 1.27)
					(thickness 0.15)
				)
				(justify left bottom)
				(hide yes)
			)
		)
		(property "Footprint" "antmicro-footprints:C_0402_1005Metric"
			(at 365.76 224.79 0)
			(effects
				(font
					(size 1.27 1.27)
					(thickness 0.15)
				)
				(justify left bottom)
				(hide yes)
			)
		)
		(property "Datasheet" "https://www.murata.com/products/productdetail?partno=GRM155R61H104KE14%23"
			(at 368.3 224.79 0)
			(effects
				(font
					(size 1.27 1.27)
					(thickness 0.15)
				)
				(justify left bottom)
				(hide yes)
			)
		)
		(property "Description" ""
			(at 353.06 245.11 0)
			(effects
				(font
					(size 1.27 1.27)
				)
			)
		)
		(property "Manufacturer" "Murata"
			(at 373.38 224.79 0)
			(effects
				(font
					(size 1.27 1.27)
					(thickness 0.15)
				)
				(justify left bottom)
				(hide yes)
			)
		)
		(property "MPN" "GRM155R61H104KE14D"
			(at 370.84 224.79 0)
			(effects
				(font
					(size 1.27 1.27)
					(thickness 0.15)
				)
				(justify left bottom)
				(hide yes)
			)
		)
		(property "Val" "100n"
			(at 353.695 244.475 90)
			(effects
				(font
					(size 1.27 1.27)
					(thickness 0.15)
				)
				(justify right)
			)
		)
		(property "License" "Apache-2.0"
			(at 375.92 224.79 0)
			(effects
				(font
					(size 1.27 1.27)
					(thickness 0.15)
				)
				(justify left bottom)
				(hide yes)
			)
		)
		(property "Author" "Antmicro"
			(at 378.46 224.79 0)
			(effects
				(font
					(size 1.27 1.27)
					(thickness 0.15)
				)
				(justify left bottom)
				(hide yes)
			)
		)
		(property "Voltage" "50V"
			(at 381 224.79 0)
			(effects
				(font
					(size 1.27 1.27)
				)
				(justify left bottom)
				(hide yes)
			)
		)
		(property "Dielectric" "X5R"
			(at 383.54 224.79 0)
			(effects
				(font
					(size 1.27 1.27)
				)
				(justify left bottom)
				(hide yes)
			)
		)
		(pin "1"
		)
		(pin "2"
		)
		(instances
			(project "k410t-devboard"
				(path ""
					(reference "C248")
					(unit 1)
				)
			)
		)
	)
	(symbol
		(lib_id "antmicroResistors0402:R_12k_0402")
		(at 163.83 236.22 90)
		(unit 1)
		(exclude_from_sim no)
		(in_bom yes)
		(on_board yes)
		(dnp no)
		(property "Reference" "R160"
			(at 165.1 232.41 90)
			(effects
				(font
					(size 1.27 1.27)
				)
				(justify right)
			)
		)
		(property "Value" "R_12k_0402"
			(at 176.53 215.9 0)
			(effects
				(font
					(size 1.27 1.27)
					(thickness 0.15)
				)
				(justify left bottom)
				(hide yes)
			)
		)
		(property "Footprint" "antmicro-footprints:R_0402_1005Metric"
			(at 179.07 215.9 0)
			(effects
				(font
					(size 1.27 1.27)
					(thickness 0.15)
				)
				(justify left bottom)
				(hide yes)
			)
		)
		(property "Datasheet" "https://www.bourns.com/docs/product-datasheets/cr.pdf"
			(at 181.61 215.9 0)
			(effects
				(font
					(size 1.27 1.27)
					(thickness 0.15)
				)
				(justify left bottom)
				(hide yes)
			)
		)
		(property "Description" ""
			(at 163.83 236.22 0)
			(effects
				(font
					(size 1.27 1.27)
				)
			)
		)
		(property "Manufacturer" "Bourns"
			(at 186.69 215.9 0)
			(effects
				(font
					(size 1.27 1.27)
					(thickness 0.15)
				)
				(justify left bottom)
				(hide yes)
			)
		)
		(property "MPN" "CR0402-FX-1202GLF"
			(at 184.15 215.9 0)
			(effects
				(font
					(size 1.27 1.27)
					(thickness 0.15)
				)
				(justify left bottom)
				(hide yes)
			)
		)
		(property "Val" "12k"
			(at 165.1 234.95 90)
			(effects
				(font
					(size 1.27 1.27)
					(thickness 0.15)
				)
				(justify right)
			)
		)
		(property "License" "Apache-2.0"
			(at 189.23 215.9 0)
			(effects
				(font
					(size 1.27 1.27)
					(thickness 0.15)
				)
				(justify left bottom)
				(hide yes)
			)
		)
		(property "Author" "Antmicro"
			(at 191.77 215.9 0)
			(effects
				(font
					(size 1.27 1.27)
					(thickness 0.15)
				)
				(justify left bottom)
				(hide yes)
			)
		)
		(property "Tolerance" "1%"
			(at 173.99 215.9 0)
			(effects
				(font
					(size 1.27 1.27)
				)
				(justify left bottom)
				(hide yes)
			)
		)
		(pin "1"
		)
		(pin "2"
		)
		(instances
			(project "k410t-devboard"
				(path ""
					(reference "R160")
					(unit 1)
				)
			)
		)
	)
	(symbol
		(lib_id "antmicroTVSDiodes:TPD4E05U06QDQARQ1")
		(at 57.15 45.72 90)
		(mirror x)
		(unit 1)
		(exclude_from_sim no)
		(in_bom yes)
		(on_board yes)
		(dnp no)
		(property "Reference" "U16"
			(at 54.61 57.15 90)
			(effects
				(font
					(size 1.27 1.27)
				)
				(justify right)
			)
		)
		(property "Value" "TPD4E05U06QDQARQ1"
			(at 61.595 59.055 90)
			(effects
				(font
					(size 1.27 1.27)
					(thickness 0.15)
				)
				(hide yes)
			)
		)
		(property "Footprint" "antmicro-footprints:USON-10_2.5x1mm_P0.5mm"
			(at 62.23 69.85 0)
			(effects
				(font
					(size 1.27 1.27)
					(thickness 0.15)
				)
				(justify left bottom)
				(hide yes)
			)
		)
		(property "Datasheet" "https://www.ti.com/lit/ds/symlink/tpd4e05u06-q1.pdf?HQS=dis-mous-null-mousermode-dsf-pf-null-wwe&ts=1663591265741&ref_url=https%253A%252F%252Fwww.mouser.com%252F"
			(at 64.77 69.85 0)
			(effects
				(font
					(size 1.27 1.27)
					(thickness 0.15)
				)
				(justify left bottom)
				(hide yes)
			)
		)
		(property "Description" ""
			(at 57.15 45.72 0)
			(effects
				(font
					(size 1.27 1.27)
				)
			)
		)
		(property "Manufacturer" "Texas Instruments"
			(at 67.31 69.85 0)
			(effects
				(font
					(size 1.27 1.27)
					(thickness 0.15)
				)
				(justify left bottom)
				(hide yes)
			)
		)
		(property "MPN" "TPD4E05U06QDQARQ1"
			(at 54.61 59.69 90)
			(effects
				(font
					(size 1.27 1.27)
					(thickness 0.15)
				)
				(justify right)
			)
		)
		(property "Author" "Antmicro"
			(at 72.39 69.85 0)
			(effects
				(font
					(size 1.27 1.27)
					(thickness 0.15)
				)
				(justify left bottom)
				(hide yes)
			)
		)
		(property "License" "Apache-2.0"
			(at 74.93 69.85 0)
			(effects
				(font
					(size 1.27 1.27)
					(thickness 0.15)
				)
				(justify left bottom)
				(hide yes)
			)
		)
		(pin "1"
		)
		(pin "10"
		)
		(pin "2"
		)
		(pin "3"
		)
		(pin "4"
		)
		(pin "5"
		)
		(pin "6"
		)
		(pin "7"
		)
		(pin "8"
		)
		(pin "9"
		)
		(instances
			(project "k410t-devboard"
				(path ""
					(reference "U16")
					(unit 1)
				)
			)
		)
	)
	(symbol
		(lib_id "antmicroResistors0402:R_330R_0402")
		(at 80.01 250.19 0)
		(unit 1)
		(exclude_from_sim no)
		(in_bom yes)
		(on_board yes)
		(dnp no)
		(property "Reference" "R152"
			(at 85.09 250.19 0)
			(effects
				(font
					(size 1.524 1.524)
				)
				(justify left bottom)
			)
		)
		(property "Value" "R_330R_0402"
			(at 100.33 262.89 0)
			(effects
				(font
					(size 1.27 1.27)
					(thickness 0.15)
				)
				(justify left bottom)
				(hide yes)
			)
		)
		(property "Footprint" "antmicro-footprints:R_0402_1005Metric"
			(at 100.33 265.43 0)
			(effects
				(font
					(size 1.27 1.27)
					(thickness 0.15)
				)
				(justify left bottom)
				(hide yes)
			)
		)
		(property "Datasheet" "https://www.bourns.com/docs/product-datasheets/cr.pdf"
			(at 100.33 267.97 0)
			(effects
				(font
					(size 1.27 1.27)
					(thickness 0.15)
				)
				(justify left bottom)
				(hide yes)
			)
		)
		(property "Description" ""
			(at 80.01 250.19 0)
			(effects
				(font
					(size 1.27 1.27)
				)
			)
		)
		(property "Manufacturer" "Bourns"
			(at 100.33 273.05 0)
			(effects
				(font
					(size 1.27 1.27)
					(thickness 0.15)
				)
				(justify left bottom)
				(hide yes)
			)
		)
		(property "MPN" "CR0402-FX-3300GLF"
			(at 100.33 270.51 0)
			(effects
				(font
					(size 1.27 1.27)
					(thickness 0.15)
				)
				(justify left bottom)
				(hide yes)
			)
		)
		(property "Val" "330R"
			(at 74.93 250.19 0)
			(effects
				(font
					(size 1.27 1.27)
					(thickness 0.15)
				)
				(justify left bottom)
			)
		)
		(property "License" "Apache-2.0"
			(at 100.33 275.59 0)
			(effects
				(font
					(size 1.27 1.27)
					(thickness 0.15)
				)
				(justify left bottom)
				(hide yes)
			)
		)
		(property "Author" "Antmicro"
			(at 100.33 278.13 0)
			(effects
				(font
					(size 1.27 1.27)
					(thickness 0.15)
				)
				(justify left bottom)
				(hide yes)
			)
		)
		(property "Tolerance" "1%"
			(at 100.33 260.35 0)
			(effects
				(font
					(size 1.27 1.27)
				)
				(justify left bottom)
				(hide yes)
			)
		)
		(pin "1"
		)
		(pin "2"
		)
		(instances
			(project "k410t-devboard"
				(path ""
					(reference "R152")
					(unit 1)
				)
			)
		)
	)
	(symbol
		(lib_id "antmicroCapacitors0402:C_100n_0402")
		(at 341.63 245.11 90)
		(unit 1)
		(exclude_from_sim no)
		(in_bom yes)
		(on_board yes)
		(dnp no)
		(property "Reference" "C247"
			(at 342.265 240.665 90)
			(effects
				(font
					(size 1.27 1.27)
				)
				(justify right)
			)
		)
		(property "Value" "C_100n_0402"
			(at 351.79 224.79 0)
			(effects
				(font
					(size 1.27 1.27)
					(thickness 0.15)
				)
				(justify left bottom)
				(hide yes)
			)
		)
		(property "Footprint" "antmicro-footprints:C_0402_1005Metric"
			(at 354.33 224.79 0)
			(effects
				(font
					(size 1.27 1.27)
					(thickness 0.15)
				)
				(justify left bottom)
				(hide yes)
			)
		)
		(property "Datasheet" "https://www.murata.com/products/productdetail?partno=GRM155R61H104KE14%23"
			(at 356.87 224.79 0)
			(effects
				(font
					(size 1.27 1.27)
					(thickness 0.15)
				)
				(justify left bottom)
				(hide yes)
			)
		)
		(property "Description" ""
			(at 341.63 245.11 0)
			(effects
				(font
					(size 1.27 1.27)
				)
			)
		)
		(property "Manufacturer" "Murata"
			(at 361.95 224.79 0)
			(effects
				(font
					(size 1.27 1.27)
					(thickness 0.15)
				)
				(justify left bottom)
				(hide yes)
			)
		)
		(property "MPN" "GRM155R61H104KE14D"
			(at 359.41 224.79 0)
			(effects
				(font
					(size 1.27 1.27)
					(thickness 0.15)
				)
				(justify left bottom)
				(hide yes)
			)
		)
		(property "Val" "100n"
			(at 342.265 244.475 90)
			(effects
				(font
					(size 1.27 1.27)
					(thickness 0.15)
				)
				(justify right)
			)
		)
		(property "License" "Apache-2.0"
			(at 364.49 224.79 0)
			(effects
				(font
					(size 1.27 1.27)
					(thickness 0.15)
				)
				(justify left bottom)
				(hide yes)
			)
		)
		(property "Author" "Antmicro"
			(at 367.03 224.79 0)
			(effects
				(font
					(size 1.27 1.27)
					(thickness 0.15)
				)
				(justify left bottom)
				(hide yes)
			)
		)
		(property "Voltage" "50V"
			(at 369.57 224.79 0)
			(effects
				(font
					(size 1.27 1.27)
				)
				(justify left bottom)
				(hide yes)
			)
		)
		(property "Dielectric" "X5R"
			(at 372.11 224.79 0)
			(effects
				(font
					(size 1.27 1.27)
				)
				(justify left bottom)
				(hide yes)
			)
		)
		(pin "1"
		)
		(pin "2"
		)
		(instances
			(project "k410t-devboard"
				(path ""
					(reference "C247")
					(unit 1)
				)
			)
		)
	)
	(symbol
		(lib_id "antmicropower:PWR_FLAG")
		(at 64.77 130.81 0)
		(unit 1)
		(exclude_from_sim no)
		(in_bom yes)
		(on_board yes)
		(dnp no)
		(property "Reference" "#FLG05"
			(at 64.77 128.905 0)
			(effects
				(font
					(size 1.27 1.27)
				)
				(hide yes)
			)
		)
		(property "Value" "PWR_FLAG"
			(at 64.77 127 0)
			(effects
				(font
					(size 1.27 1.27)
				)
			)
		)
		(property "Footprint" ""
			(at 64.77 130.81 0)
			(effects
				(font
					(size 1.27 1.27)
				)
				(hide yes)
			)
		)
		(property "Datasheet" ""
			(at 64.77 130.81 0)
			(effects
				(font
					(size 1.27 1.27)
				)
				(hide yes)
			)
		)
		(property "Description" ""
			(at 64.77 130.81 0)
			(effects
				(font
					(size 1.27 1.27)
				)
			)
		)
		(pin "1"
		)
		(instances
			(project "k410t-devboard"
				(path ""
					(reference "#FLG05")
					(unit 1)
				)
			)
		)
	)
	(symbol
		(lib_id "antmicropower:GND")
		(at 52.07 50.8 0)
		(unit 1)
		(exclude_from_sim no)
		(in_bom yes)
		(on_board yes)
		(dnp no)
		(property "Reference" "#PWR0200"
			(at 52.07 57.15 0)
			(effects
				(font
					(size 1.27 1.27)
				)
				(hide yes)
			)
		)
		(property "Value" "GND"
			(at 52.07 54.61 0)
			(effects
				(font
					(size 1.27 1.27)
				)
			)
		)
		(property "Footprint" ""
			(at 60.96 58.42 0)
			(effects
				(font
					(size 1.27 1.27)
					(thickness 0.15)
				)
				(justify left bottom)
				(hide yes)
			)
		)
		(property "Datasheet" ""
			(at 60.96 63.5 0)
			(effects
				(font
					(size 1.27 1.27)
					(thickness 0.15)
				)
				(justify left bottom)
				(hide yes)
			)
		)
		(property "Description" ""
			(at 52.07 50.8 0)
			(effects
				(font
					(size 1.27 1.27)
				)
			)
		)
		(property "Author" "Antmicro"
			(at 60.96 58.42 0)
			(effects
				(font
					(size 1.27 1.27)
					(thickness 0.15)
				)
				(justify left bottom)
				(hide yes)
			)
		)
		(property "License" "Apache-2.0"
			(at 60.96 60.96 0)
			(effects
				(font
					(size 1.27 1.27)
					(thickness 0.15)
				)
				(justify left bottom)
				(hide yes)
			)
		)
		(pin "1"
		)
		(instances
			(project "k410t-devboard"
				(path ""
					(reference "#PWR0200")
					(unit 1)
				)
			)
		)
	)
	(symbol
		(lib_id "antmicropower:GND")
		(at 72.39 48.26 0)
		(mirror y)
		(unit 1)
		(exclude_from_sim no)
		(in_bom yes)
		(on_board yes)
		(dnp no)
		(property "Reference" "#PWR0207"
			(at 72.39 54.61 0)
			(effects
				(font
					(size 1.27 1.27)
				)
				(hide yes)
			)
		)
		(property "Value" "GND"
			(at 72.39 52.07 0)
			(effects
				(font
					(size 1.27 1.27)
				)
			)
		)
		(property "Footprint" ""
			(at 63.5 55.88 0)
			(effects
				(font
					(size 1.27 1.27)
					(thickness 0.15)
				)
				(justify left bottom)
				(hide yes)
			)
		)
		(property "Datasheet" ""
			(at 63.5 60.96 0)
			(effects
				(font
					(size 1.27 1.27)
					(thickness 0.15)
				)
				(justify left bottom)
				(hide yes)
			)
		)
		(property "Description" ""
			(at 72.39 48.26 0)
			(effects
				(font
					(size 1.27 1.27)
				)
			)
		)
		(property "Author" "Antmicro"
			(at 63.5 55.88 0)
			(effects
				(font
					(size 1.27 1.27)
					(thickness 0.15)
				)
				(justify left bottom)
				(hide yes)
			)
		)
		(property "License" "Apache-2.0"
			(at 63.5 58.42 0)
			(effects
				(font
					(size 1.27 1.27)
					(thickness 0.15)
				)
				(justify left bottom)
				(hide yes)
			)
		)
		(pin "1"
		)
		(instances
			(project "k410t-devboard"
				(path ""
					(reference "#PWR0207")
					(unit 1)
				)
			)
		)
	)
	(symbol
		(lib_id "antmicropower:+3.3V")
		(at 377.19 185.42 0)
		(mirror y)
		(unit 1)
		(exclude_from_sim no)
		(in_bom yes)
		(on_board yes)
		(dnp no)
		(property "Reference" "#PWR0247"
			(at 377.19 189.23 0)
			(effects
				(font
					(size 1.27 1.27)
				)
				(hide yes)
			)
		)
		(property "Value" "+3V3"
			(at 377.19 181.864 0)
			(effects
				(font
					(size 1.27 1.27)
				)
			)
		)
		(property "Footprint" ""
			(at 377.19 185.42 0)
			(effects
				(font
					(size 1.27 1.27)
				)
				(hide yes)
			)
		)
		(property "Datasheet" ""
			(at 377.19 185.42 0)
			(effects
				(font
					(size 1.27 1.27)
				)
				(hide yes)
			)
		)
		(property "Description" ""
			(at 377.19 185.42 0)
			(effects
				(font
					(size 1.27 1.27)
				)
			)
		)
		(pin "1"
		)
		(instances
			(project "k410t-devboard"
				(path ""
					(reference "#PWR0247")
					(unit 1)
				)
			)
		)
	)
	(symbol
		(lib_id "antmicropower:GND")
		(at 128.27 176.53 0)
		(mirror y)
		(unit 1)
		(exclude_from_sim no)
		(in_bom yes)
		(on_board yes)
		(dnp no)
		(property "Reference" "#PWR0223"
			(at 128.27 182.88 0)
			(effects
				(font
					(size 1.27 1.27)
				)
				(hide yes)
			)
		)
		(property "Value" "GND"
			(at 128.27 180.34 0)
			(effects
				(font
					(size 1.27 1.27)
				)
			)
		)
		(property "Footprint" ""
			(at 119.38 184.15 0)
			(effects
				(font
					(size 1.27 1.27)
					(thickness 0.15)
				)
				(justify left bottom)
				(hide yes)
			)
		)
		(property "Datasheet" ""
			(at 119.38 189.23 0)
			(effects
				(font
					(size 1.27 1.27)
					(thickness 0.15)
				)
				(justify left bottom)
				(hide yes)
			)
		)
		(property "Description" ""
			(at 128.27 176.53 0)
			(effects
				(font
					(size 1.27 1.27)
				)
			)
		)
		(property "Author" "Antmicro"
			(at 119.38 184.15 0)
			(effects
				(font
					(size 1.27 1.27)
					(thickness 0.15)
				)
				(justify left bottom)
				(hide yes)
			)
		)
		(property "License" "Apache-2.0"
			(at 119.38 186.69 0)
			(effects
				(font
					(size 1.27 1.27)
					(thickness 0.15)
				)
				(justify left bottom)
				(hide yes)
			)
		)
		(pin "1"
		)
		(instances
			(project "k410t-devboard"
				(path ""
					(reference "#PWR0223")
					(unit 1)
				)
			)
		)
	)
	(symbol
		(lib_id "antmicroUSBConnectors:USB-C_GCT_USB4105-GF-A")
		(at 236.22 43.18 0)
		(unit 1)
		(exclude_from_sim no)
		(in_bom yes)
		(on_board yes)
		(dnp no)
		(fields_autoplaced yes)
		(property "Reference" "J14"
			(at 222.885 35.56 0)
			(effects
				(font
					(size 1.27 1.27)
					(thickness 0.15)
				)
			)
		)
		(property "Value" "USB-C_GCT_USB4105-GF-A"
			(at 246.6975 38.735 0)
			(effects
				(font
					(size 1.27 1.27)
					(thickness 0.15)
				)
				(hide yes)
			)
		)
		(property "Footprint" "antmicro-footprints:USB-C_Receptacle_GCT_USB4105-GF-A"
			(at 274.32 50.8 0)
			(effects
				(font
					(size 1.27 1.27)
					(thickness 0.15)
				)
				(justify left bottom)
				(hide yes)
			)
		)
		(property "Datasheet" "https://gct.co/files/drawings/usb4105.pdf"
			(at 274.32 53.34 0)
			(effects
				(font
					(size 1.27 1.27)
					(thickness 0.15)
				)
				(justify left bottom)
				(hide yes)
			)
		)
		(property "Description" ""
			(at 236.22 43.18 0)
			(effects
				(font
					(size 1.27 1.27)
				)
			)
		)
		(property "Manufacturer" "GCT"
			(at 274.32 55.88 0)
			(effects
				(font
					(size 1.27 1.27)
					(thickness 0.15)
				)
				(justify left bottom)
				(hide yes)
			)
		)
		(property "MPN" "USB4105-GF-A"
			(at 222.885 38.1 0)
			(effects
				(font
					(size 1.27 1.27)
					(thickness 0.15)
				)
			)
		)
		(property "Author" "Antmicro"
			(at 274.32 60.96 0)
			(effects
				(font
					(size 1.27 1.27)
					(thickness 0.15)
				)
				(justify left bottom)
				(hide yes)
			)
		)
		(property "License" "Apache-2.0"
			(at 274.32 63.5 0)
			(effects
				(font
					(size 1.27 1.27)
					(thickness 0.15)
				)
				(justify left bottom)
				(hide yes)
			)
		)
		(property "VSD_Class" "USB-C"
			(at 274.32 66.04 0)
			(effects
				(font
					(size 1.27 1.27)
				)
				(justify left bottom)
				(hide yes)
			)
		)
		(pin "A1"
		)
		(pin "A12"
		)
		(pin "A4"
		)
		(pin "A5"
		)
		(pin "A6"
		)
		(pin "A7"
		)
		(pin "A8"
		)
		(pin "A9"
		)
		(pin "B1"
		)
		(pin "B12"
		)
		(pin "B4"
		)
		(pin "B5"
		)
		(pin "B6"
		)
		(pin "B7"
		)
		(pin "B8"
		)
		(pin "B9"
		)
		(pin "SH"
		)
		(instances
			(project "k410t-devboard"
				(path ""
					(reference "J14")
					(unit 1)
				)
			)
		)
	)
	(symbol
		(lib_id "antmicropower:+3.3V")
		(at 397.51 236.22 0)
		(unit 1)
		(exclude_from_sim no)
		(in_bom yes)
		(on_board yes)
		(dnp no)
		(property "Reference" "#PWR0249"
			(at 397.51 240.03 0)
			(effects
				(font
					(size 1.27 1.27)
				)
				(hide yes)
			)
		)
		(property "Value" "+3V3"
			(at 397.51 232.664 0)
			(effects
				(font
					(size 1.27 1.27)
				)
			)
		)
		(property "Footprint" ""
			(at 397.51 236.22 0)
			(effects
				(font
					(size 1.27 1.27)
				)
				(hide yes)
			)
		)
		(property "Datasheet" ""
			(at 397.51 236.22 0)
			(effects
				(font
					(size 1.27 1.27)
				)
				(hide yes)
			)
		)
		(property "Description" ""
			(at 397.51 236.22 0)
			(effects
				(font
					(size 1.27 1.27)
				)
			)
		)
		(pin "1"
		)
		(instances
			(project "k410t-devboard"
				(path ""
					(reference "#PWR0249")
					(unit 1)
				)
			)
		)
	)
	(symbol
		(lib_id "antmicropower:GND")
		(at 123.19 256.54 0)
		(unit 1)
		(exclude_from_sim no)
		(in_bom yes)
		(on_board yes)
		(dnp no)
		(property "Reference" "#PWR0219"
			(at 123.19 262.89 0)
			(effects
				(font
					(size 1.27 1.27)
				)
				(hide yes)
			)
		)
		(property "Value" "GND"
			(at 123.19 260.35 0)
			(effects
				(font
					(size 1.27 1.27)
				)
			)
		)
		(property "Footprint" ""
			(at 132.08 264.16 0)
			(effects
				(font
					(size 1.27 1.27)
					(thickness 0.15)
				)
				(justify left bottom)
				(hide yes)
			)
		)
		(property "Datasheet" ""
			(at 132.08 269.24 0)
			(effects
				(font
					(size 1.27 1.27)
					(thickness 0.15)
				)
				(justify left bottom)
				(hide yes)
			)
		)
		(property "Description" ""
			(at 123.19 256.54 0)
			(effects
				(font
					(size 1.27 1.27)
				)
			)
		)
		(property "Author" "Antmicro"
			(at 132.08 264.16 0)
			(effects
				(font
					(size 1.27 1.27)
					(thickness 0.15)
				)
				(justify left bottom)
				(hide yes)
			)
		)
		(property "License" "Apache-2.0"
			(at 132.08 266.7 0)
			(effects
				(font
					(size 1.27 1.27)
					(thickness 0.15)
				)
				(justify left bottom)
				(hide yes)
			)
		)
		(pin "1"
		)
		(instances
			(project "k410t-devboard"
				(path ""
					(reference "#PWR0219")
					(unit 1)
				)
			)
		)
	)
	(symbol
		(lib_id "antmicropower:GND")
		(at 157.48 35.56 0)
		(unit 1)
		(exclude_from_sim no)
		(in_bom yes)
		(on_board yes)
		(dnp no)
		(fields_autoplaced yes)
		(property "Reference" "#PWR0233"
			(at 157.48 41.91 0)
			(effects
				(font
					(size 1.27 1.27)
				)
				(hide yes)
			)
		)
		(property "Value" "GND"
			(at 157.48 40.005 0)
			(effects
				(font
					(size 1.27 1.27)
				)
			)
		)
		(property "Footprint" ""
			(at 166.37 43.18 0)
			(effects
				(font
					(size 1.27 1.27)
					(thickness 0.15)
				)
				(justify left bottom)
				(hide yes)
			)
		)
		(property "Datasheet" ""
			(at 166.37 48.26 0)
			(effects
				(font
					(size 1.27 1.27)
					(thickness 0.15)
				)
				(justify left bottom)
				(hide yes)
			)
		)
		(property "Description" ""
			(at 157.48 35.56 0)
			(effects
				(font
					(size 1.27 1.27)
				)
			)
		)
		(property "Author" "Antmicro"
			(at 166.37 43.18 0)
			(effects
				(font
					(size 1.27 1.27)
					(thickness 0.15)
				)
				(justify left bottom)
				(hide yes)
			)
		)
		(property "License" "Apache-2.0"
			(at 166.37 45.72 0)
			(effects
				(font
					(size 1.27 1.27)
					(thickness 0.15)
				)
				(justify left bottom)
				(hide yes)
			)
		)
		(pin "1"
		)
		(instances
			(project "k410t-devboard"
				(path ""
					(reference "#PWR0233")
					(unit 1)
				)
			)
		)
	)
	(symbol
		(lib_id "antmicroResistors0402:R_33R_0402")
		(at 340.36 180.34 0)
		(unit 1)
		(exclude_from_sim no)
		(in_bom yes)
		(on_board yes)
		(dnp no)
		(property "Reference" "R183"
			(at 347.98 179.07 0)
			(effects
				(font
					(size 1.27 1.27)
				)
			)
		)
		(property "Value" "R_33R_0402"
			(at 360.68 193.04 0)
			(effects
				(font
					(size 1.27 1.27)
					(thickness 0.15)
				)
				(justify left bottom)
				(hide yes)
			)
		)
		(property "Footprint" "antmicro-footprints:R_0402_1005Metric"
			(at 360.68 195.58 0)
			(effects
				(font
					(size 1.27 1.27)
					(thickness 0.15)
				)
				(justify left bottom)
				(hide yes)
			)
		)
		(property "Datasheet" "https://www.bourns.com/docs/product-datasheets/cr.pdf"
			(at 360.68 198.12 0)
			(effects
				(font
					(size 1.27 1.27)
					(thickness 0.15)
				)
				(justify left bottom)
				(hide yes)
			)
		)
		(property "Description" ""
			(at 340.36 180.34 0)
			(effects
				(font
					(size 1.27 1.27)
				)
			)
		)
		(property "Manufacturer" "Bourns"
			(at 360.68 203.2 0)
			(effects
				(font
					(size 1.27 1.27)
					(thickness 0.15)
				)
				(justify left bottom)
				(hide yes)
			)
		)
		(property "MPN" "CR0402-FX-33R0GLF"
			(at 360.68 200.66 0)
			(effects
				(font
					(size 1.27 1.27)
					(thickness 0.15)
				)
				(justify left bottom)
				(hide yes)
			)
		)
		(property "Val" "33R"
			(at 338.455 179.07 0)
			(effects
				(font
					(size 1.27 1.27)
					(thickness 0.15)
				)
			)
		)
		(property "License" "Apache-2.0"
			(at 360.68 205.74 0)
			(effects
				(font
					(size 1.27 1.27)
					(thickness 0.15)
				)
				(justify left bottom)
				(hide yes)
			)
		)
		(property "Author" "Antmicro"
			(at 360.68 208.28 0)
			(effects
				(font
					(size 1.27 1.27)
					(thickness 0.15)
				)
				(justify left bottom)
				(hide yes)
			)
		)
		(property "Tolerance" "1%"
			(at 360.68 190.5 0)
			(effects
				(font
					(size 1.27 1.27)
				)
				(justify left bottom)
				(hide yes)
			)
		)
		(pin "1"
		)
		(pin "2"
		)
		(instances
			(project "k410t-devboard"
				(path ""
					(reference "R183")
					(unit 1)
				)
			)
		)
	)
	(symbol
		(lib_id "antmicropower:GND")
		(at 355.6 33.02 0)
		(mirror y)
		(unit 1)
		(exclude_from_sim no)
		(in_bom yes)
		(on_board yes)
		(dnp no)
		(property "Reference" "#PWR0272"
			(at 355.6 39.37 0)
			(effects
				(font
					(size 1.27 1.27)
				)
				(hide yes)
			)
		)
		(property "Value" "GND"
			(at 355.6 36.83 0)
			(effects
				(font
					(size 1.27 1.27)
				)
			)
		)
		(property "Footprint" ""
			(at 346.71 40.64 0)
			(effects
				(font
					(size 1.27 1.27)
					(thickness 0.15)
				)
				(justify left bottom)
				(hide yes)
			)
		)
		(property "Datasheet" ""
			(at 346.71 45.72 0)
			(effects
				(font
					(size 1.27 1.27)
					(thickness 0.15)
				)
				(justify left bottom)
				(hide yes)
			)
		)
		(property "Description" ""
			(at 355.6 33.02 0)
			(effects
				(font
					(size 1.27 1.27)
				)
			)
		)
		(property "Author" "Antmicro"
			(at 346.71 40.64 0)
			(effects
				(font
					(size 1.27 1.27)
					(thickness 0.15)
				)
				(justify left bottom)
				(hide yes)
			)
		)
		(property "License" "Apache-2.0"
			(at 346.71 43.18 0)
			(effects
				(font
					(size 1.27 1.27)
					(thickness 0.15)
				)
				(justify left bottom)
				(hide yes)
			)
		)
		(pin "1"
		)
		(instances
			(project "k410t-devboard"
				(path ""
					(reference "#PWR0272")
					(unit 1)
				)
			)
		)
	)
	(symbol
		(lib_id "antmicroLogicTranslatorsLevelShifters:74LVC1T45GM")
		(at 252.73 140.97 0)
		(unit 1)
		(exclude_from_sim no)
		(in_bom yes)
		(on_board yes)
		(dnp no)
		(property "Reference" "U48"
			(at 260.985 135.89 0)
			(effects
				(font
					(size 1.27 1.27)
				)
			)
		)
		(property "Value" "74LVC1T45GM"
			(at 260.985 138.43 0)
			(effects
				(font
					(size 1.27 1.27)
					(thickness 0.15)
				)
			)
		)
		(property "Footprint" "antmicro-footprints:SOT-886"
			(at 283.21 151.13 0)
			(effects
				(font
					(size 1.27 1.27)
					(thickness 0.15)
				)
				(justify left bottom)
				(hide yes)
			)
		)
		(property "Datasheet" "http://www.ti.com/general/docs/suppproductinfo.tsp?distId=10&gotoUrl=http%3A%2F%2Fwww.ti.com%2Flit%2Fgpn%2Fsn74lvc1t45"
			(at 283.21 153.67 0)
			(effects
				(font
					(size 1.27 1.27)
					(thickness 0.15)
				)
				(justify left bottom)
				(hide yes)
			)
		)
		(property "Description" ""
			(at 252.73 140.97 0)
			(effects
				(font
					(size 1.27 1.27)
				)
			)
		)
		(property "MPN" "74LVC1T45GM-Q100X"
			(at 283.21 156.21 0)
			(effects
				(font
					(size 1.27 1.27)
					(thickness 0.15)
				)
				(justify left bottom)
				(hide yes)
			)
		)
		(property "Manufacturer" "Nexperia"
			(at 283.21 158.75 0)
			(effects
				(font
					(size 1.27 1.27)
					(thickness 0.15)
				)
				(justify left bottom)
				(hide yes)
			)
		)
		(property "Author" "Antmicro"
			(at 283.21 161.29 0)
			(effects
				(font
					(size 1.27 1.27)
					(thickness 0.15)
				)
				(justify left bottom)
				(hide yes)
			)
		)
		(property "License" "Apache-2.0"
			(at 283.21 163.83 0)
			(effects
				(font
					(size 1.27 1.27)
					(thickness 0.15)
				)
				(justify left bottom)
				(hide yes)
			)
		)
		(pin "1"
		)
		(pin "2"
		)
		(pin "3"
		)
		(pin "4"
		)
		(pin "5"
		)
		(pin "6"
		)
		(instances
			(project "k410t-devboard"
				(path ""
					(reference "U48")
					(unit 1)
				)
			)
		)
	)
	(symbol
		(lib_id "antmicroResistors0402:R_12k_0402")
		(at 77.47 92.71 90)
		(unit 1)
		(exclude_from_sim no)
		(in_bom yes)
		(on_board yes)
		(dnp no)
		(property "Reference" "R346"
			(at 78.74 88.9 90)
			(effects
				(font
					(size 1.27 1.27)
				)
				(justify right)
			)
		)
		(property "Value" "R_12k_0402"
			(at 90.17 72.39 0)
			(effects
				(font
					(size 1.27 1.27)
					(thickness 0.15)
				)
				(justify left bottom)
				(hide yes)
			)
		)
		(property "Footprint" "antmicro-footprints:R_0402_1005Metric"
			(at 92.71 72.39 0)
			(effects
				(font
					(size 1.27 1.27)
					(thickness 0.15)
				)
				(justify left bottom)
				(hide yes)
			)
		)
		(property "Datasheet" "https://www.bourns.com/docs/product-datasheets/cr.pdf"
			(at 95.25 72.39 0)
			(effects
				(font
					(size 1.27 1.27)
					(thickness 0.15)
				)
				(justify left bottom)
				(hide yes)
			)
		)
		(property "Description" ""
			(at 77.47 92.71 0)
			(effects
				(font
					(size 1.27 1.27)
				)
			)
		)
		(property "Manufacturer" "Bourns"
			(at 100.33 72.39 0)
			(effects
				(font
					(size 1.27 1.27)
					(thickness 0.15)
				)
				(justify left bottom)
				(hide yes)
			)
		)
		(property "MPN" "CR0402-FX-1202GLF"
			(at 97.79 72.39 0)
			(effects
				(font
					(size 1.27 1.27)
					(thickness 0.15)
				)
				(justify left bottom)
				(hide yes)
			)
		)
		(property "Val" "12k"
			(at 78.74 91.44 90)
			(effects
				(font
					(size 1.27 1.27)
					(thickness 0.15)
				)
				(justify right)
			)
		)
		(property "License" "Apache-2.0"
			(at 102.87 72.39 0)
			(effects
				(font
					(size 1.27 1.27)
					(thickness 0.15)
				)
				(justify left bottom)
				(hide yes)
			)
		)
		(property "Author" "Antmicro"
			(at 105.41 72.39 0)
			(effects
				(font
					(size 1.27 1.27)
					(thickness 0.15)
				)
				(justify left bottom)
				(hide yes)
			)
		)
		(property "Tolerance" "1%"
			(at 87.63 72.39 0)
			(effects
				(font
					(size 1.27 1.27)
				)
				(justify left bottom)
				(hide yes)
			)
		)
		(pin "1"
		)
		(pin "2"
		)
		(instances
			(project "k410t-devboard"
				(path ""
					(reference "R346")
					(unit 1)
				)
			)
		)
	)
	(symbol
		(lib_id "antmicroFerriteBeadsandChips:FB_600Z_0.5A_Murata-BLM18AG_0603")
		(at 97.79 125.73 0)
		(unit 1)
		(exclude_from_sim no)
		(in_bom yes)
		(on_board yes)
		(dnp no)
		(fields_autoplaced yes)
		(property "Reference" "FB6"
			(at 100.2919 119.38 0)
			(effects
				(font
					(size 1.27 1.27)
				)
			)
		)
		(property "Value" "FB_600Z_0.5A_Murata-BLM18AG_0603"
			(at 100.2919 121.92 0)
			(effects
				(font
					(size 1.27 1.27)
					(thickness 0.15)
				)
				(hide yes)
			)
		)
		(property "Footprint" "antmicro-footprints:FB_0603_1608Metric"
			(at 111.76 130.81 0)
			(effects
				(font
					(size 1.27 1.27)
					(thickness 0.15)
				)
				(justify left bottom)
				(hide yes)
			)
		)
		(property "Datasheet" "https://www.murata.com/en-us/products/productdata/8796738650142/ENFA0003.pdf"
			(at 111.76 133.35 0)
			(effects
				(font
					(size 1.27 1.27)
					(thickness 0.15)
				)
				(justify left bottom)
				(hide yes)
			)
		)
		(property "Description" ""
			(at 97.79 125.73 0)
			(effects
				(font
					(size 1.27 1.27)
				)
			)
		)
		(property "MPN" "BLM18AG601SN1D"
			(at 111.76 135.89 0)
			(effects
				(font
					(size 1.27 1.27)
					(thickness 0.15)
				)
				(justify left bottom)
				(hide yes)
			)
		)
		(property "Manufacturer" "Murata"
			(at 111.76 138.43 0)
			(effects
				(font
					(size 1.27 1.27)
					(thickness 0.15)
				)
				(justify left bottom)
				(hide yes)
			)
		)
		(property "Author" "Antmicro"
			(at 111.76 140.97 0)
			(effects
				(font
					(size 1.27 1.27)
					(thickness 0.15)
				)
				(justify left bottom)
				(hide yes)
			)
		)
		(property "License" "Apache-2.0"
			(at 111.76 143.51 0)
			(effects
				(font
					(size 1.27 1.27)
					(thickness 0.15)
				)
				(justify left bottom)
				(hide yes)
			)
		)
		(property "Val" "600Z/0.5A"
			(at 100.2919 121.92 0)
			(effects
				(font
					(size 1.27 1.27)
				)
			)
		)
		(property "Current" ""
			(at 118.11 148.59 0)
			(effects
				(font
					(size 1.27 1.27)
					(thickness 0.15)
				)
				(justify left bottom)
				(hide yes)
			)
		)
		(pin "1"
		)
		(pin "2"
		)
		(instances
			(project "k410t-devboard"
				(path ""
					(reference "FB6")
					(unit 1)
				)
			)
		)
	)
	(symbol
		(lib_id "antmicropower:GND")
		(at 146.05 238.76 0)
		(unit 1)
		(exclude_from_sim no)
		(in_bom yes)
		(on_board yes)
		(dnp no)
		(property "Reference" "#PWR0227"
			(at 146.05 245.11 0)
			(effects
				(font
					(size 1.27 1.27)
				)
				(hide yes)
			)
		)
		(property "Value" "GND"
			(at 146.05 242.57 0)
			(effects
				(font
					(size 1.27 1.27)
				)
			)
		)
		(property "Footprint" ""
			(at 154.94 246.38 0)
			(effects
				(font
					(size 1.27 1.27)
					(thickness 0.15)
				)
				(justify left bottom)
				(hide yes)
			)
		)
		(property "Datasheet" ""
			(at 154.94 251.46 0)
			(effects
				(font
					(size 1.27 1.27)
					(thickness 0.15)
				)
				(justify left bottom)
				(hide yes)
			)
		)
		(property "Description" ""
			(at 146.05 238.76 0)
			(effects
				(font
					(size 1.27 1.27)
				)
			)
		)
		(property "Author" "Antmicro"
			(at 154.94 246.38 0)
			(effects
				(font
					(size 1.27 1.27)
					(thickness 0.15)
				)
				(justify left bottom)
				(hide yes)
			)
		)
		(property "License" "Apache-2.0"
			(at 154.94 248.92 0)
			(effects
				(font
					(size 1.27 1.27)
					(thickness 0.15)
				)
				(justify left bottom)
				(hide yes)
			)
		)
		(pin "1"
		)
		(instances
			(project "k410t-devboard"
				(path ""
					(reference "#PWR0227")
					(unit 1)
				)
			)
		)
	)
	(symbol
		(lib_id "antmicroResistors0402:R_10k_0402")
		(at 341.63 81.28 90)
		(unit 1)
		(exclude_from_sim no)
		(in_bom yes)
		(on_board yes)
		(dnp no)
		(property "Reference" "R348"
			(at 342.9 77.47 90)
			(effects
				(font
					(size 1.27 1.27)
				)
				(justify right)
			)
		)
		(property "Value" "R_10k_0402"
			(at 354.33 60.96 0)
			(effects
				(font
					(size 1.27 1.27)
					(thickness 0.15)
				)
				(justify left bottom)
				(hide yes)
			)
		)
		(property "Footprint" "antmicro-footprints:R_0402_1005Metric"
			(at 356.87 60.96 0)
			(effects
				(font
					(size 1.27 1.27)
					(thickness 0.15)
				)
				(justify left bottom)
				(hide yes)
			)
		)
		(property "Datasheet" "https://www.bourns.com/docs/product-datasheets/cr.pdf"
			(at 359.41 60.96 0)
			(effects
				(font
					(size 1.27 1.27)
					(thickness 0.15)
				)
				(justify left bottom)
				(hide yes)
			)
		)
		(property "Description" ""
			(at 341.63 81.28 0)
			(effects
				(font
					(size 1.27 1.27)
				)
			)
		)
		(property "Manufacturer" "Bourns"
			(at 364.49 60.96 0)
			(effects
				(font
					(size 1.27 1.27)
					(thickness 0.15)
				)
				(justify left bottom)
				(hide yes)
			)
		)
		(property "MPN" "CR0402-FX-1002GLF"
			(at 361.95 60.96 0)
			(effects
				(font
					(size 1.27 1.27)
					(thickness 0.15)
				)
				(justify left bottom)
				(hide yes)
			)
		)
		(property "Val" "10k"
			(at 342.9 80.01 90)
			(effects
				(font
					(size 1.27 1.27)
					(thickness 0.15)
				)
				(justify right)
			)
		)
		(property "License" "Apache-2.0"
			(at 367.03 60.96 0)
			(effects
				(font
					(size 1.27 1.27)
					(thickness 0.15)
				)
				(justify left bottom)
				(hide yes)
			)
		)
		(property "Author" "Antmicro"
			(at 369.57 60.96 0)
			(effects
				(font
					(size 1.27 1.27)
					(thickness 0.15)
				)
				(justify left bottom)
				(hide yes)
			)
		)
		(property "Tolerance" "1%"
			(at 351.79 60.96 0)
			(effects
				(font
					(size 1.27 1.27)
				)
				(justify left bottom)
				(hide yes)
			)
		)
		(pin "1"
		)
		(pin "2"
		)
		(instances
			(project "k410t-devboard"
				(path ""
					(reference "R348")
					(unit 1)
				)
			)
		)
	)
	(symbol
		(lib_id "antmicroDiodesRectifiersSingle:BAT54-02V-G3-08")
		(at 346.71 215.9 0)
		(unit 1)
		(exclude_from_sim no)
		(in_bom yes)
		(on_board yes)
		(dnp no)
		(property "Reference" "D30"
			(at 349.25 220.345 0)
			(effects
				(font
					(size 1.27 1.27)
				)
			)
		)
		(property "Value" "BAT54-02V-G3-08"
			(at 349.25 222.885 0)
			(effects
				(font
					(size 1.27 1.27)
					(thickness 0.15)
				)
			)
		)
		(property "Footprint" "antmicro-footprints:SOD-523"
			(at 368.3 226.06 0)
			(effects
				(font
					(size 1.27 1.27)
					(thickness 0.15)
				)
				(justify left bottom)
				(hide yes)
			)
		)
		(property "Datasheet" "https://www.vishay.com/docs/85633/bat5402v.pdf"
			(at 368.3 228.6 0)
			(effects
				(font
					(size 1.27 1.27)
					(thickness 0.15)
				)
				(justify left bottom)
				(hide yes)
			)
		)
		(property "Description" ""
			(at 346.71 215.9 0)
			(effects
				(font
					(size 1.27 1.27)
				)
			)
		)
		(property "MPN" "BAT54-02V-G3-08"
			(at 368.3 231.14 0)
			(effects
				(font
					(size 1.27 1.27)
					(thickness 0.15)
				)
				(justify left bottom)
				(hide yes)
			)
		)
		(property "Manufacturer" "Vishay"
			(at 368.3 233.68 0)
			(effects
				(font
					(size 1.27 1.27)
					(thickness 0.15)
				)
				(justify left bottom)
				(hide yes)
			)
		)
		(property "Author" "Antmicro"
			(at 368.3 236.22 0)
			(effects
				(font
					(size 1.27 1.27)
					(thickness 0.15)
				)
				(justify left bottom)
				(hide yes)
			)
		)
		(property "License" "Apache-2.0"
			(at 368.3 238.76 0)
			(effects
				(font
					(size 1.27 1.27)
					(thickness 0.15)
				)
				(justify left bottom)
				(hide yes)
			)
		)
		(property "Public" "False"
			(at 367.03 233.68 0)
			(effects
				(font
					(size 1.27 1.27)
				)
				(justify left bottom)
				(hide yes)
			)
		)
		(pin "1"
		)
		(pin "2"
		)
		(instances
			(project "k410t-devboard"
				(path ""
					(reference "D30")
					(unit 1)
				)
			)
		)
	)
	(symbol
		(lib_id "antmicroResistors0402:R_10k_0402")
		(at 35.56 71.12 270)
		(unit 1)
		(exclude_from_sim no)
		(in_bom yes)
		(on_board yes)
		(dnp no)
		(property "Reference" "R343"
			(at 36.83 72.39 90)
			(effects
				(font
					(size 1.27 1.27)
				)
				(justify left)
			)
		)
		(property "Value" "R_10k_0402"
			(at 22.86 91.44 0)
			(effects
				(font
					(size 1.27 1.27)
					(thickness 0.15)
				)
				(justify left bottom)
				(hide yes)
			)
		)
		(property "Footprint" "antmicro-footprints:R_0402_1005Metric"
			(at 20.32 91.44 0)
			(effects
				(font
					(size 1.27 1.27)
					(thickness 0.15)
				)
				(justify left bottom)
				(hide yes)
			)
		)
		(property "Datasheet" "https://www.bourns.com/docs/product-datasheets/cr.pdf"
			(at 17.78 91.44 0)
			(effects
				(font
					(size 1.27 1.27)
					(thickness 0.15)
				)
				(justify left bottom)
				(hide yes)
			)
		)
		(property "Description" ""
			(at 35.56 71.12 0)
			(effects
				(font
					(size 1.27 1.27)
				)
			)
		)
		(property "Manufacturer" "Bourns"
			(at 12.7 91.44 0)
			(effects
				(font
					(size 1.27 1.27)
					(thickness 0.15)
				)
				(justify left bottom)
				(hide yes)
			)
		)
		(property "MPN" "CR0402-FX-1002GLF"
			(at 15.24 91.44 0)
			(effects
				(font
					(size 1.27 1.27)
					(thickness 0.15)
				)
				(justify left bottom)
				(hide yes)
			)
		)
		(property "Val" "10k"
			(at 36.83 74.93 90)
			(effects
				(font
					(size 1.27 1.27)
					(thickness 0.15)
				)
				(justify left)
			)
		)
		(property "License" "Apache-2.0"
			(at 10.16 91.44 0)
			(effects
				(font
					(size 1.27 1.27)
					(thickness 0.15)
				)
				(justify left bottom)
				(hide yes)
			)
		)
		(property "Author" "Antmicro"
			(at 7.62 91.44 0)
			(effects
				(font
					(size 1.27 1.27)
					(thickness 0.15)
				)
				(justify left bottom)
				(hide yes)
			)
		)
		(property "Tolerance" "1%"
			(at 25.4 91.44 0)
			(effects
				(font
					(size 1.27 1.27)
				)
				(justify left bottom)
				(hide yes)
			)
		)
		(pin "1"
		)
		(pin "2"
		)
		(instances
			(project "k410t-devboard"
				(path ""
					(reference "R343")
					(unit 1)
				)
			)
		)
	)
	(symbol
		(lib_id "antmicroResistors0402:R_33R_0402")
		(at 106.68 41.91 0)
		(unit 1)
		(exclude_from_sim no)
		(in_bom yes)
		(on_board yes)
		(dnp no)
		(property "Reference" "R155"
			(at 114.3 40.64 0)
			(effects
				(font
					(size 1.27 1.27)
				)
			)
		)
		(property "Value" "R_33R_0402"
			(at 127 54.61 0)
			(effects
				(font
					(size 1.27 1.27)
					(thickness 0.15)
				)
				(justify left bottom)
				(hide yes)
			)
		)
		(property "Footprint" "antmicro-footprints:R_0402_1005Metric"
			(at 127 57.15 0)
			(effects
				(font
					(size 1.27 1.27)
					(thickness 0.15)
				)
				(justify left bottom)
				(hide yes)
			)
		)
		(property "Datasheet" "https://www.bourns.com/docs/product-datasheets/cr.pdf"
			(at 127 59.69 0)
			(effects
				(font
					(size 1.27 1.27)
					(thickness 0.15)
				)
				(justify left bottom)
				(hide yes)
			)
		)
		(property "Description" ""
			(at 106.68 41.91 0)
			(effects
				(font
					(size 1.27 1.27)
				)
			)
		)
		(property "Manufacturer" "Bourns"
			(at 127 64.77 0)
			(effects
				(font
					(size 1.27 1.27)
					(thickness 0.15)
				)
				(justify left bottom)
				(hide yes)
			)
		)
		(property "MPN" "CR0402-FX-33R0GLF"
			(at 127 62.23 0)
			(effects
				(font
					(size 1.27 1.27)
					(thickness 0.15)
				)
				(justify left bottom)
				(hide yes)
			)
		)
		(property "Val" "33R"
			(at 104.775 40.64 0)
			(effects
				(font
					(size 1.27 1.27)
					(thickness 0.15)
				)
			)
		)
		(property "License" "Apache-2.0"
			(at 127 67.31 0)
			(effects
				(font
					(size 1.27 1.27)
					(thickness 0.15)
				)
				(justify left bottom)
				(hide yes)
			)
		)
		(property "Author" "Antmicro"
			(at 127 69.85 0)
			(effects
				(font
					(size 1.27 1.27)
					(thickness 0.15)
				)
				(justify left bottom)
				(hide yes)
			)
		)
		(property "Tolerance" "1%"
			(at 127 52.07 0)
			(effects
				(font
					(size 1.27 1.27)
				)
				(justify left bottom)
				(hide yes)
			)
		)
		(pin "1"
		)
		(pin "2"
		)
		(instances
			(project "k410t-devboard"
				(path ""
					(reference "R155")
					(unit 1)
				)
			)
		)
	)
	(symbol
		(lib_id "antmicroCapacitors0402:C_100n_0402")
		(at 146.05 237.49 90)
		(unit 1)
		(exclude_from_sim no)
		(in_bom yes)
		(on_board yes)
		(dnp no)
		(fields_autoplaced yes)
		(property "Reference" "C224"
			(at 148.59 233.6735 90)
			(effects
				(font
					(size 1.27 1.27)
				)
				(justify right)
			)
		)
		(property "Value" "C_100n_0402"
			(at 156.21 217.17 0)
			(effects
				(font
					(size 1.27 1.27)
					(thickness 0.15)
				)
				(justify left bottom)
				(hide yes)
			)
		)
		(property "Footprint" "antmicro-footprints:C_0402_1005Metric"
			(at 158.75 217.17 0)
			(effects
				(font
					(size 1.27 1.27)
					(thickness 0.15)
				)
				(justify left bottom)
				(hide yes)
			)
		)
		(property "Datasheet" "https://www.murata.com/products/productdetail?partno=GRM155R61H104KE14%23"
			(at 161.29 217.17 0)
			(effects
				(font
					(size 1.27 1.27)
					(thickness 0.15)
				)
				(justify left bottom)
				(hide yes)
			)
		)
		(property "Description" ""
			(at 146.05 237.49 0)
			(effects
				(font
					(size 1.27 1.27)
				)
			)
		)
		(property "Manufacturer" "Murata"
			(at 166.37 217.17 0)
			(effects
				(font
					(size 1.27 1.27)
					(thickness 0.15)
				)
				(justify left bottom)
				(hide yes)
			)
		)
		(property "MPN" "GRM155R61H104KE14D"
			(at 163.83 217.17 0)
			(effects
				(font
					(size 1.27 1.27)
					(thickness 0.15)
				)
				(justify left bottom)
				(hide yes)
			)
		)
		(property "Val" "100n"
			(at 148.59 236.2135 90)
			(effects
				(font
					(size 1.27 1.27)
					(thickness 0.15)
				)
				(justify right)
			)
		)
		(property "License" "Apache-2.0"
			(at 168.91 217.17 0)
			(effects
				(font
					(size 1.27 1.27)
					(thickness 0.15)
				)
				(justify left bottom)
				(hide yes)
			)
		)
		(property "Author" "Antmicro"
			(at 171.45 217.17 0)
			(effects
				(font
					(size 1.27 1.27)
					(thickness 0.15)
				)
				(justify left bottom)
				(hide yes)
			)
		)
		(property "Voltage" "50V"
			(at 173.99 217.17 0)
			(effects
				(font
					(size 1.27 1.27)
				)
				(justify left bottom)
				(hide yes)
			)
		)
		(property "Dielectric" "X5R"
			(at 176.53 217.17 0)
			(effects
				(font
					(size 1.27 1.27)
				)
				(justify left bottom)
				(hide yes)
			)
		)
		(pin "1"
		)
		(pin "2"
		)
		(instances
			(project "k410t-devboard"
				(path ""
					(reference "C224")
					(unit 1)
				)
			)
		)
	)
	(symbol
		(lib_id "antmicropower:+3.3V")
		(at 307.34 21.59 0)
		(unit 1)
		(exclude_from_sim no)
		(in_bom yes)
		(on_board yes)
		(dnp no)
		(property "Reference" "#PWR0229"
			(at 307.34 25.4 0)
			(effects
				(font
					(size 1.27 1.27)
				)
				(hide yes)
			)
		)
		(property "Value" "+3V3"
			(at 307.34 17.78 0)
			(effects
				(font
					(size 1.27 1.27)
				)
			)
		)
		(property "Footprint" ""
			(at 307.34 21.59 0)
			(effects
				(font
					(size 1.27 1.27)
				)
				(hide yes)
			)
		)
		(property "Datasheet" ""
			(at 307.34 21.59 0)
			(effects
				(font
					(size 1.27 1.27)
				)
				(hide yes)
			)
		)
		(property "Description" ""
			(at 307.34 21.59 0)
			(effects
				(font
					(size 1.27 1.27)
				)
			)
		)
		(pin "1"
		)
		(instances
			(project "k410t-devboard"
				(path ""
					(reference "#PWR0229")
					(unit 1)
				)
			)
		)
	)
	(symbol
		(lib_id "antmicropower:GND")
		(at 318.77 34.29 0)
		(unit 1)
		(exclude_from_sim no)
		(in_bom yes)
		(on_board yes)
		(dnp no)
		(property "Reference" "#PWR0265"
			(at 318.77 40.64 0)
			(effects
				(font
					(size 1.27 1.27)
				)
				(hide yes)
			)
		)
		(property "Value" "GND"
			(at 318.77 38.1 0)
			(effects
				(font
					(size 1.27 1.27)
				)
			)
		)
		(property "Footprint" ""
			(at 327.66 41.91 0)
			(effects
				(font
					(size 1.27 1.27)
					(thickness 0.15)
				)
				(justify left bottom)
				(hide yes)
			)
		)
		(property "Datasheet" ""
			(at 327.66 46.99 0)
			(effects
				(font
					(size 1.27 1.27)
					(thickness 0.15)
				)
				(justify left bottom)
				(hide yes)
			)
		)
		(property "Description" ""
			(at 318.77 34.29 0)
			(effects
				(font
					(size 1.27 1.27)
				)
			)
		)
		(property "Author" "Antmicro"
			(at 327.66 41.91 0)
			(effects
				(font
					(size 1.27 1.27)
					(thickness 0.15)
				)
				(justify left bottom)
				(hide yes)
			)
		)
		(property "License" "Apache-2.0"
			(at 327.66 44.45 0)
			(effects
				(font
					(size 1.27 1.27)
					(thickness 0.15)
				)
				(justify left bottom)
				(hide yes)
			)
		)
		(pin "1"
		)
		(instances
			(project "k410t-devboard"
				(path ""
					(reference "#PWR0265")
					(unit 1)
				)
			)
		)
	)
	(symbol
		(lib_id "antmicroLogicShiftRegisters:SN74HC595B")
		(at 121.92 234.95 0)
		(mirror y)
		(unit 1)
		(exclude_from_sim no)
		(in_bom yes)
		(on_board yes)
		(dnp no)
		(fields_autoplaced yes)
		(property "Reference" "U18"
			(at 111.76 227.33 0)
			(effects
				(font
					(size 1.27 1.27)
				)
			)
		)
		(property "Value" "SN74HC595B"
			(at 111.76 229.235 0)
			(effects
				(font
					(size 1.27 1.27)
					(thickness 0.15)
				)
				(hide yes)
			)
		)
		(property "Footprint" "antmicro-footprints:X1QFN-16-1EP_2.5x2.5mm"
			(at 86.36 245.11 0)
			(effects
				(font
					(size 1.27 1.27)
					(thickness 0.15)
				)
				(justify left bottom)
				(hide yes)
			)
		)
		(property "Datasheet" "https://www.ti.com/general/docs/suppproductinfo.tsp?distId=26&gotoUrl=https://www.ti.com/lit/gpn/sn74hc595b"
			(at 86.36 247.65 0)
			(effects
				(font
					(size 1.27 1.27)
					(thickness 0.15)
				)
				(justify left bottom)
				(hide yes)
			)
		)
		(property "Description" ""
			(at 121.92 234.95 0)
			(effects
				(font
					(size 1.27 1.27)
				)
			)
		)
		(property "Manufacturer" "Texas Instruments"
			(at 86.36 250.19 0)
			(effects
				(font
					(size 1.27 1.27)
					(thickness 0.15)
				)
				(justify left bottom)
				(hide yes)
			)
		)
		(property "MPN" "SN74HC595BRWNR"
			(at 111.76 229.87 0)
			(effects
				(font
					(size 1.27 1.27)
					(thickness 0.15)
				)
			)
		)
		(property "Author" "Antmicro"
			(at 86.36 255.27 0)
			(effects
				(font
					(size 1.27 1.27)
					(thickness 0.15)
				)
				(justify left bottom)
				(hide yes)
			)
		)
		(property "License" "Apache-2.0"
			(at 86.36 257.81 0)
			(effects
				(font
					(size 1.27 1.27)
					(thickness 0.15)
				)
				(justify left bottom)
				(hide yes)
			)
		)
		(pin "1"
		)
		(pin "10"
		)
		(pin "11"
		)
		(pin "12"
		)
		(pin "13"
		)
		(pin "14"
		)
		(pin "15"
		)
		(pin "16"
		)
		(pin "17"
		)
		(pin "2"
		)
		(pin "3"
		)
		(pin "4"
		)
		(pin "5"
		)
		(pin "6"
		)
		(pin "7"
		)
		(pin "8"
		)
		(pin "9"
		)
		(instances
			(project "k410t-devboard"
				(path ""
					(reference "U18")
					(unit 1)
				)
			)
		)
	)
	(symbol
		(lib_id "antmicropower:GND")
		(at 309.88 102.87 0)
		(mirror y)
		(unit 1)
		(exclude_from_sim no)
		(in_bom yes)
		(on_board yes)
		(dnp no)
		(property "Reference" "#PWR0261"
			(at 309.88 109.22 0)
			(effects
				(font
					(size 1.27 1.27)
				)
				(hide yes)
			)
		)
		(property "Value" "GND"
			(at 309.88 106.68 0)
			(effects
				(font
					(size 1.27 1.27)
				)
			)
		)
		(property "Footprint" ""
			(at 300.99 110.49 0)
			(effects
				(font
					(size 1.27 1.27)
					(thickness 0.15)
				)
				(justify left bottom)
				(hide yes)
			)
		)
		(property "Datasheet" ""
			(at 300.99 115.57 0)
			(effects
				(font
					(size 1.27 1.27)
					(thickness 0.15)
				)
				(justify left bottom)
				(hide yes)
			)
		)
		(property "Description" ""
			(at 309.88 102.87 0)
			(effects
				(font
					(size 1.27 1.27)
				)
			)
		)
		(property "Author" "Antmicro"
			(at 300.99 110.49 0)
			(effects
				(font
					(size 1.27 1.27)
					(thickness 0.15)
				)
				(justify left bottom)
				(hide yes)
			)
		)
		(property "License" "Apache-2.0"
			(at 300.99 113.03 0)
			(effects
				(font
					(size 1.27 1.27)
					(thickness 0.15)
				)
				(justify left bottom)
				(hide yes)
			)
		)
		(pin "1"
		)
		(instances
			(project "k410t-devboard"
				(path ""
					(reference "#PWR0261")
					(unit 1)
				)
			)
		)
	)
	(symbol
		(lib_id "antmicroInterfaceControllers:FT4232H_VQFN")
		(at 173.99 143.51 0)
		(unit 1)
		(exclude_from_sim no)
		(in_bom yes)
		(on_board yes)
		(dnp no)
		(property "Reference" "U20"
			(at 194.31 135.89 0)
			(effects
				(font
					(size 1.27 1.27)
				)
			)
		)
		(property "Value" "FT4232H_VQFN"
			(at 194.31 138.43 0)
			(effects
				(font
					(size 1.27 1.27)
					(thickness 0.15)
				)
				(hide yes)
			)
		)
		(property "Footprint" "antmicro-footprints:QFN-56-1EP_8x8mm_P0.5mm"
			(at 229.87 151.13 0)
			(effects
				(font
					(size 1.27 1.27)
					(thickness 0.15)
				)
				(justify left bottom)
				(hide yes)
			)
		)
		(property "Datasheet" "https://www.ftdichip.com/Support/Documents/DataSheets/ICs/DS_FT4232H.pdf"
			(at 229.87 153.67 0)
			(effects
				(font
					(size 1.27 1.27)
					(thickness 0.15)
				)
				(justify left bottom)
				(hide yes)
			)
		)
		(property "Description" ""
			(at 173.99 143.51 0)
			(effects
				(font
					(size 1.27 1.27)
				)
			)
		)
		(property "Manufacturer" "FTDI Chip"
			(at 229.87 156.21 0)
			(effects
				(font
					(size 1.27 1.27)
					(thickness 0.15)
				)
				(justify left bottom)
				(hide yes)
			)
		)
		(property "MPN" "FT4232H-56Q-REEL"
			(at 194.31 138.43 0)
			(effects
				(font
					(size 1.27 1.27)
					(thickness 0.15)
				)
			)
		)
		(property "Author" "Antmicro"
			(at 229.87 161.29 0)
			(effects
				(font
					(size 1.27 1.27)
					(thickness 0.15)
				)
				(justify left bottom)
				(hide yes)
			)
		)
		(property "License" "Apache-2.0"
			(at 229.87 163.83 0)
			(effects
				(font
					(size 1.27 1.27)
					(thickness 0.15)
				)
				(justify left bottom)
				(hide yes)
			)
		)
		(pin "1"
		)
		(pin "10"
		)
		(pin "11"
		)
		(pin "12"
		)
		(pin "13"
		)
		(pin "14"
		)
		(pin "15"
		)
		(pin "16"
		)
		(pin "17"
		)
		(pin "18"
		)
		(pin "19"
		)
		(pin "2"
		)
		(pin "20"
		)
		(pin "21"
		)
		(pin "22"
		)
		(pin "23"
		)
		(pin "24"
		)
		(pin "25"
		)
		(pin "26"
		)
		(pin "27"
		)
		(pin "28"
		)
		(pin "29"
		)
		(pin "3"
		)
		(pin "30"
		)
		(pin "31"
		)
		(pin "32"
		)
		(pin "33"
		)
		(pin "34"
		)
		(pin "35"
		)
		(pin "36"
		)
		(pin "37"
		)
		(pin "38"
		)
		(pin "39"
		)
		(pin "4"
		)
		(pin "40"
		)
		(pin "41"
		)
		(pin "42"
		)
		(pin "43"
		)
		(pin "44"
		)
		(pin "45"
		)
		(pin "46"
		)
		(pin "47"
		)
		(pin "48"
		)
		(pin "49"
		)
		(pin "5"
		)
		(pin "50"
		)
		(pin "51"
		)
		(pin "52"
		)
		(pin "53"
		)
		(pin "54"
		)
		(pin "55"
		)
		(pin "56"
		)
		(pin "57"
		)
		(pin "6"
		)
		(pin "7"
		)
		(pin "8"
		)
		(pin "9"
		)
		(instances
			(project "k410t-devboard"
				(path ""
					(reference "U20")
					(unit 1)
				)
			)
		)
	)
	(symbol
		(lib_id "antmicroResistors0402:R_1k5_0402")
		(at 300.99 50.8 0)
		(unit 1)
		(exclude_from_sim no)
		(in_bom yes)
		(on_board yes)
		(dnp no)
		(property "Reference" "R171"
			(at 308.61 49.53 0)
			(effects
				(font
					(size 1.27 1.27)
				)
			)
		)
		(property "Value" "R_1k5_0402"
			(at 321.31 63.5 0)
			(effects
				(font
					(size 1.27 1.27)
					(thickness 0.15)
				)
				(justify left bottom)
				(hide yes)
			)
		)
		(property "Footprint" "antmicro-footprints:R_0402_1005Metric"
			(at 321.31 66.04 0)
			(effects
				(font
					(size 1.27 1.27)
					(thickness 0.15)
				)
				(justify left bottom)
				(hide yes)
			)
		)
		(property "Datasheet" "https://www.bourns.com/docs/product-datasheets/cr.pdf"
			(at 321.31 68.58 0)
			(effects
				(font
					(size 1.27 1.27)
					(thickness 0.15)
				)
				(justify left bottom)
				(hide yes)
			)
		)
		(property "Description" ""
			(at 300.99 50.8 0)
			(effects
				(font
					(size 1.27 1.27)
				)
			)
		)
		(property "Manufacturer" "Bourns"
			(at 321.31 73.66 0)
			(effects
				(font
					(size 1.27 1.27)
					(thickness 0.15)
				)
				(justify left bottom)
				(hide yes)
			)
		)
		(property "MPN" "CR0402-FX-1501GLF"
			(at 321.31 71.12 0)
			(effects
				(font
					(size 1.27 1.27)
					(thickness 0.15)
				)
				(justify left bottom)
				(hide yes)
			)
		)
		(property "Val" "1k5"
			(at 299.085 49.53 0)
			(effects
				(font
					(size 1.27 1.27)
					(thickness 0.15)
				)
			)
		)
		(property "License" "Apache-2.0"
			(at 321.31 76.2 0)
			(effects
				(font
					(size 1.27 1.27)
					(thickness 0.15)
				)
				(justify left bottom)
				(hide yes)
			)
		)
		(property "Author" "Antmicro"
			(at 321.31 78.74 0)
			(effects
				(font
					(size 1.27 1.27)
					(thickness 0.15)
				)
				(justify left bottom)
				(hide yes)
			)
		)
		(property "Tolerance" "1%"
			(at 321.31 60.96 0)
			(effects
				(font
					(size 1.27 1.27)
				)
				(justify left bottom)
				(hide yes)
			)
		)
		(pin "1"
		)
		(pin "2"
		)
		(instances
			(project "k410t-devboard"
				(path ""
					(reference "R171")
					(unit 1)
				)
			)
		)
	)
	(symbol
		(lib_id "antmicroResistors0402:R_33R_0402")
		(at 238.76 189.23 0)
		(unit 1)
		(exclude_from_sim no)
		(in_bom yes)
		(on_board yes)
		(dnp no)
		(property "Reference" "R162"
			(at 243.84 187.96 0)
			(effects
				(font
					(size 1.27 1.27)
				)
				(justify left)
			)
		)
		(property "Value" "R_33R_0402"
			(at 259.08 201.93 0)
			(effects
				(font
					(size 1.27 1.27)
					(thickness 0.15)
				)
				(justify left bottom)
				(hide yes)
			)
		)
		(property "Footprint" "antmicro-footprints:R_0402_1005Metric"
			(at 259.08 204.47 0)
			(effects
				(font
					(size 1.27 1.27)
					(thickness 0.15)
				)
				(justify left bottom)
				(hide yes)
			)
		)
		(property "Datasheet" "https://www.bourns.com/docs/product-datasheets/cr.pdf"
			(at 259.08 207.01 0)
			(effects
				(font
					(size 1.27 1.27)
					(thickness 0.15)
				)
				(justify left bottom)
				(hide yes)
			)
		)
		(property "Description" ""
			(at 238.76 189.23 0)
			(effects
				(font
					(size 1.27 1.27)
				)
			)
		)
		(property "Manufacturer" "Bourns"
			(at 259.08 212.09 0)
			(effects
				(font
					(size 1.27 1.27)
					(thickness 0.15)
				)
				(justify left bottom)
				(hide yes)
			)
		)
		(property "MPN" "CR0402-FX-33R0GLF"
			(at 259.08 209.55 0)
			(effects
				(font
					(size 1.27 1.27)
					(thickness 0.15)
				)
				(justify left bottom)
				(hide yes)
			)
		)
		(property "Val" "33R"
			(at 234.95 189.23 0)
			(effects
				(font
					(size 1.27 1.27)
					(thickness 0.15)
				)
				(justify left bottom)
			)
		)
		(property "License" "Apache-2.0"
			(at 259.08 214.63 0)
			(effects
				(font
					(size 1.27 1.27)
					(thickness 0.15)
				)
				(justify left bottom)
				(hide yes)
			)
		)
		(property "Author" "Antmicro"
			(at 259.08 217.17 0)
			(effects
				(font
					(size 1.27 1.27)
					(thickness 0.15)
				)
				(justify left bottom)
				(hide yes)
			)
		)
		(property "Tolerance" "1%"
			(at 259.08 199.39 0)
			(effects
				(font
					(size 1.27 1.27)
				)
				(justify left bottom)
				(hide yes)
			)
		)
		(pin "1"
		)
		(pin "2"
		)
		(instances
			(project "k410t-devboard"
				(path ""
					(reference "R162")
					(unit 1)
				)
			)
		)
	)
	(symbol
		(lib_id "antmicropower:GND")
		(at 162.56 134.62 0)
		(mirror y)
		(unit 1)
		(exclude_from_sim no)
		(in_bom yes)
		(on_board yes)
		(dnp no)
		(property "Reference" "#PWR0238"
			(at 162.56 140.97 0)
			(effects
				(font
					(size 1.27 1.27)
				)
				(hide yes)
			)
		)
		(property "Value" "GND"
			(at 162.56 138.43 0)
			(effects
				(font
					(size 1.27 1.27)
				)
			)
		)
		(property "Footprint" ""
			(at 153.67 142.24 0)
			(effects
				(font
					(size 1.27 1.27)
					(thickness 0.15)
				)
				(justify left bottom)
				(hide yes)
			)
		)
		(property "Datasheet" ""
			(at 153.67 147.32 0)
			(effects
				(font
					(size 1.27 1.27)
					(thickness 0.15)
				)
				(justify left bottom)
				(hide yes)
			)
		)
		(property "Description" ""
			(at 162.56 134.62 0)
			(effects
				(font
					(size 1.27 1.27)
				)
			)
		)
		(property "Author" "Antmicro"
			(at 153.67 142.24 0)
			(effects
				(font
					(size 1.27 1.27)
					(thickness 0.15)
				)
				(justify left bottom)
				(hide yes)
			)
		)
		(property "License" "Apache-2.0"
			(at 153.67 144.78 0)
			(effects
				(font
					(size 1.27 1.27)
					(thickness 0.15)
				)
				(justify left bottom)
				(hide yes)
			)
		)
		(pin "1"
		)
		(instances
			(project "k410t-devboard"
				(path ""
					(reference "#PWR0238")
					(unit 1)
				)
			)
		)
	)
	(symbol
		(lib_id "antmicroResistors0402:R_0R_0402")
		(at 21.59 90.17 90)
		(unit 1)
		(exclude_from_sim no)
		(in_bom yes)
		(on_board yes)
		(dnp no)
		(property "Reference" "R344"
			(at 22.86 86.36 90)
			(effects
				(font
					(size 1.27 1.27)
				)
				(justify right)
			)
		)
		(property "Value" "R_0R_0402"
			(at 34.29 69.85 0)
			(effects
				(font
					(size 1.27 1.27)
					(thickness 0.15)
				)
				(justify left bottom)
				(hide yes)
			)
		)
		(property "Footprint" "antmicro-footprints:R_0402_1005Metric"
			(at 36.83 69.85 0)
			(effects
				(font
					(size 1.27 1.27)
					(thickness 0.15)
				)
				(justify left bottom)
				(hide yes)
			)
		)
		(property "Datasheet" "https://industrial.panasonic.com/cdbs/www-data/pdf/RDA0000/AOA0000C301.pdf"
			(at 39.37 69.85 0)
			(effects
				(font
					(size 1.27 1.27)
					(thickness 0.15)
				)
				(justify left bottom)
				(hide yes)
			)
		)
		(property "Description" ""
			(at 21.59 90.17 0)
			(effects
				(font
					(size 1.27 1.27)
				)
			)
		)
		(property "Manufacturer" "Panasonic"
			(at 44.45 69.85 0)
			(effects
				(font
					(size 1.27 1.27)
					(thickness 0.15)
				)
				(justify left bottom)
				(hide yes)
			)
		)
		(property "MPN" "ERJ2GE0R00X"
			(at 41.91 69.85 0)
			(effects
				(font
					(size 1.27 1.27)
					(thickness 0.15)
				)
				(justify left bottom)
				(hide yes)
			)
		)
		(property "Val" "0R"
			(at 22.86 88.9 90)
			(effects
				(font
					(size 1.27 1.27)
					(thickness 0.15)
				)
				(justify right)
			)
		)
		(property "License" "Apache-2.0"
			(at 46.99 69.85 0)
			(effects
				(font
					(size 1.27 1.27)
					(thickness 0.15)
				)
				(justify left bottom)
				(hide yes)
			)
		)
		(property "Author" "Antmicro"
			(at 49.53 69.85 0)
			(effects
				(font
					(size 1.27 1.27)
					(thickness 0.15)
				)
				(justify left bottom)
				(hide yes)
			)
		)
		(property "Tolerance" "~"
			(at 31.75 69.85 0)
			(effects
				(font
					(size 1.27 1.27)
				)
				(justify left bottom)
				(hide yes)
			)
		)
		(property "Current" "1A"
			(at 24.13 90.1699 90)
			(effects
				(font
					(size 1.27 1.27)
					(thickness 0.15)
				)
				(justify right)
				(hide yes)
			)
		)
		(pin "1"
		)
		(pin "2"
		)
		(instances
			(project "k410t-devboard"
				(path ""
					(reference "R344")
					(unit 1)
				)
			)
		)
	)
	(symbol
		(lib_id "antmicropower:GND")
		(at 171.45 237.49 0)
		(unit 1)
		(exclude_from_sim no)
		(in_bom yes)
		(on_board yes)
		(dnp no)
		(property "Reference" "#PWR0242"
			(at 171.45 243.84 0)
			(effects
				(font
					(size 1.27 1.27)
				)
				(hide yes)
			)
		)
		(property "Value" "GND"
			(at 171.45 241.3 0)
			(effects
				(font
					(size 1.27 1.27)
				)
			)
		)
		(property "Footprint" ""
			(at 180.34 245.11 0)
			(effects
				(font
					(size 1.27 1.27)
					(thickness 0.15)
				)
				(justify left bottom)
				(hide yes)
			)
		)
		(property "Datasheet" ""
			(at 180.34 250.19 0)
			(effects
				(font
					(size 1.27 1.27)
					(thickness 0.15)
				)
				(justify left bottom)
				(hide yes)
			)
		)
		(property "Description" ""
			(at 171.45 237.49 0)
			(effects
				(font
					(size 1.27 1.27)
				)
			)
		)
		(property "Author" "Antmicro"
			(at 180.34 245.11 0)
			(effects
				(font
					(size 1.27 1.27)
					(thickness 0.15)
				)
				(justify left bottom)
				(hide yes)
			)
		)
		(property "License" "Apache-2.0"
			(at 180.34 247.65 0)
			(effects
				(font
					(size 1.27 1.27)
					(thickness 0.15)
				)
				(justify left bottom)
				(hide yes)
			)
		)
		(pin "1"
		)
		(instances
			(project "k410t-devboard"
				(path ""
					(reference "#PWR0242")
					(unit 1)
				)
			)
		)
	)
	(symbol
		(lib_id "antmicroCapacitors0402:C_100n_0402")
		(at 331.47 245.11 90)
		(unit 1)
		(exclude_from_sim no)
		(in_bom yes)
		(on_board yes)
		(dnp no)
		(property "Reference" "C245"
			(at 332.105 240.665 90)
			(effects
				(font
					(size 1.27 1.27)
				)
				(justify right)
			)
		)
		(property "Value" "C_100n_0402"
			(at 341.63 224.79 0)
			(effects
				(font
					(size 1.27 1.27)
					(thickness 0.15)
				)
				(justify left bottom)
				(hide yes)
			)
		)
		(property "Footprint" "antmicro-footprints:C_0402_1005Metric"
			(at 344.17 224.79 0)
			(effects
				(font
					(size 1.27 1.27)
					(thickness 0.15)
				)
				(justify left bottom)
				(hide yes)
			)
		)
		(property "Datasheet" "https://www.murata.com/products/productdetail?partno=GRM155R61H104KE14%23"
			(at 346.71 224.79 0)
			(effects
				(font
					(size 1.27 1.27)
					(thickness 0.15)
				)
				(justify left bottom)
				(hide yes)
			)
		)
		(property "Description" ""
			(at 331.47 245.11 0)
			(effects
				(font
					(size 1.27 1.27)
				)
			)
		)
		(property "Manufacturer" "Murata"
			(at 351.79 224.79 0)
			(effects
				(font
					(size 1.27 1.27)
					(thickness 0.15)
				)
				(justify left bottom)
				(hide yes)
			)
		)
		(property "MPN" "GRM155R61H104KE14D"
			(at 349.25 224.79 0)
			(effects
				(font
					(size 1.27 1.27)
					(thickness 0.15)
				)
				(justify left bottom)
				(hide yes)
			)
		)
		(property "Val" "100n"
			(at 332.105 244.475 90)
			(effects
				(font
					(size 1.27 1.27)
					(thickness 0.15)
				)
				(justify right)
			)
		)
		(property "License" "Apache-2.0"
			(at 354.33 224.79 0)
			(effects
				(font
					(size 1.27 1.27)
					(thickness 0.15)
				)
				(justify left bottom)
				(hide yes)
			)
		)
		(property "Author" "Antmicro"
			(at 356.87 224.79 0)
			(effects
				(font
					(size 1.27 1.27)
					(thickness 0.15)
				)
				(justify left bottom)
				(hide yes)
			)
		)
		(property "Voltage" "50V"
			(at 359.41 224.79 0)
			(effects
				(font
					(size 1.27 1.27)
				)
				(justify left bottom)
				(hide yes)
			)
		)
		(property "Dielectric" "X5R"
			(at 361.95 224.79 0)
			(effects
				(font
					(size 1.27 1.27)
				)
				(justify left bottom)
				(hide yes)
			)
		)
		(pin "1"
		)
		(pin "2"
		)
		(instances
			(project "k410t-devboard"
				(path ""
					(reference "C245")
					(unit 1)
				)
			)
		)
	)
	(symbol
		(lib_id "antmicropower:GND")
		(at 127 96.52 0)
		(unit 1)
		(exclude_from_sim no)
		(in_bom yes)
		(on_board yes)
		(dnp no)
		(property "Reference" "#PWR0222"
			(at 127 102.87 0)
			(effects
				(font
					(size 1.27 1.27)
				)
				(hide yes)
			)
		)
		(property "Value" "GND"
			(at 127 100.33 0)
			(effects
				(font
					(size 1.27 1.27)
				)
			)
		)
		(property "Footprint" ""
			(at 135.89 104.14 0)
			(effects
				(font
					(size 1.27 1.27)
					(thickness 0.15)
				)
				(justify left bottom)
				(hide yes)
			)
		)
		(property "Datasheet" ""
			(at 135.89 109.22 0)
			(effects
				(font
					(size 1.27 1.27)
					(thickness 0.15)
				)
				(justify left bottom)
				(hide yes)
			)
		)
		(property "Description" ""
			(at 127 96.52 0)
			(effects
				(font
					(size 1.27 1.27)
				)
			)
		)
		(property "Author" "Antmicro"
			(at 135.89 104.14 0)
			(effects
				(font
					(size 1.27 1.27)
					(thickness 0.15)
				)
				(justify left bottom)
				(hide yes)
			)
		)
		(property "License" "Apache-2.0"
			(at 135.89 106.68 0)
			(effects
				(font
					(size 1.27 1.27)
					(thickness 0.15)
				)
				(justify left bottom)
				(hide yes)
			)
		)
		(pin "1"
		)
		(instances
			(project "k410t-devboard"
				(path ""
					(reference "#PWR0222")
					(unit 1)
				)
			)
		)
	)
	(symbol
		(lib_id "antmicroTVSDiodes:TPD4E05U06QDQARQ1")
		(at 243.84 66.04 90)
		(mirror x)
		(unit 1)
		(exclude_from_sim no)
		(in_bom yes)
		(on_board yes)
		(dnp no)
		(property "Reference" "U21"
			(at 241.3 76.2 90)
			(effects
				(font
					(size 1.27 1.27)
				)
				(justify right)
			)
		)
		(property "Value" "TPD4E05U06QDQARQ1"
			(at 241.3 78.105 90)
			(effects
				(font
					(size 1.27 1.27)
					(thickness 0.15)
				)
				(justify right)
				(hide yes)
			)
		)
		(property "Footprint" "antmicro-footprints:USON-10_2.5x1mm_P0.5mm"
			(at 248.92 90.17 0)
			(effects
				(font
					(size 1.27 1.27)
					(thickness 0.15)
				)
				(justify left bottom)
				(hide yes)
			)
		)
		(property "Datasheet" "https://www.ti.com/lit/ds/symlink/tpd4e05u06-q1.pdf?HQS=dis-mous-null-mousermode-dsf-pf-null-wwe&ts=1663591265741&ref_url=https%253A%252F%252Fwww.mouser.com%252F"
			(at 251.46 90.17 0)
			(effects
				(font
					(size 1.27 1.27)
					(thickness 0.15)
				)
				(justify left bottom)
				(hide yes)
			)
		)
		(property "Description" ""
			(at 243.84 66.04 0)
			(effects
				(font
					(size 1.27 1.27)
				)
			)
		)
		(property "Manufacturer" "Texas Instruments"
			(at 254 90.17 0)
			(effects
				(font
					(size 1.27 1.27)
					(thickness 0.15)
				)
				(justify left bottom)
				(hide yes)
			)
		)
		(property "MPN" "TPD4E05U06QDQARQ1"
			(at 241.3 78.74 90)
			(effects
				(font
					(size 1.27 1.27)
					(thickness 0.15)
				)
				(justify right)
			)
		)
		(property "Author" "Antmicro"
			(at 259.08 90.17 0)
			(effects
				(font
					(size 1.27 1.27)
					(thickness 0.15)
				)
				(justify left bottom)
				(hide yes)
			)
		)
		(property "License" "Apache-2.0"
			(at 261.62 90.17 0)
			(effects
				(font
					(size 1.27 1.27)
					(thickness 0.15)
				)
				(justify left bottom)
				(hide yes)
			)
		)
		(pin "1"
		)
		(pin "10"
		)
		(pin "2"
		)
		(pin "3"
		)
		(pin "4"
		)
		(pin "5"
		)
		(pin "6"
		)
		(pin "7"
		)
		(pin "8"
		)
		(pin "9"
		)
		(instances
			(project "k410t-devboard"
				(path ""
					(reference "U21")
					(unit 1)
				)
			)
		)
	)
	(symbol
		(lib_id "antmicroCapacitors0402:C_100n_0402")
		(at 387.35 245.11 90)
		(unit 1)
		(exclude_from_sim no)
		(in_bom yes)
		(on_board yes)
		(dnp no)
		(property "Reference" "C251"
			(at 387.985 240.665 90)
			(effects
				(font
					(size 1.27 1.27)
				)
				(justify right)
			)
		)
		(property "Value" "C_100n_0402"
			(at 397.51 224.79 0)
			(effects
				(font
					(size 1.27 1.27)
					(thickness 0.15)
				)
				(justify left bottom)
				(hide yes)
			)
		)
		(property "Footprint" "antmicro-footprints:C_0402_1005Metric"
			(at 400.05 224.79 0)
			(effects
				(font
					(size 1.27 1.27)
					(thickness 0.15)
				)
				(justify left bottom)
				(hide yes)
			)
		)
		(property "Datasheet" "https://www.murata.com/products/productdetail?partno=GRM155R61H104KE14%23"
			(at 402.59 224.79 0)
			(effects
				(font
					(size 1.27 1.27)
					(thickness 0.15)
				)
				(justify left bottom)
				(hide yes)
			)
		)
		(property "Description" ""
			(at 387.35 245.11 0)
			(effects
				(font
					(size 1.27 1.27)
				)
			)
		)
		(property "Manufacturer" "Murata"
			(at 407.67 224.79 0)
			(effects
				(font
					(size 1.27 1.27)
					(thickness 0.15)
				)
				(justify left bottom)
				(hide yes)
			)
		)
		(property "MPN" "GRM155R61H104KE14D"
			(at 405.13 224.79 0)
			(effects
				(font
					(size 1.27 1.27)
					(thickness 0.15)
				)
				(justify left bottom)
				(hide yes)
			)
		)
		(property "Val" "100n"
			(at 387.985 244.475 90)
			(effects
				(font
					(size 1.27 1.27)
					(thickness 0.15)
				)
				(justify right)
			)
		)
		(property "License" "Apache-2.0"
			(at 410.21 224.79 0)
			(effects
				(font
					(size 1.27 1.27)
					(thickness 0.15)
				)
				(justify left bottom)
				(hide yes)
			)
		)
		(property "Author" "Antmicro"
			(at 412.75 224.79 0)
			(effects
				(font
					(size 1.27 1.27)
					(thickness 0.15)
				)
				(justify left bottom)
				(hide yes)
			)
		)
		(property "Voltage" "50V"
			(at 415.29 224.79 0)
			(effects
				(font
					(size 1.27 1.27)
				)
				(justify left bottom)
				(hide yes)
			)
		)
		(property "Dielectric" "X5R"
			(at 417.83 224.79 0)
			(effects
				(font
					(size 1.27 1.27)
				)
				(justify left bottom)
				(hide yes)
			)
		)
		(pin "1"
		)
		(pin "2"
		)
		(instances
			(project "k410t-devboard"
				(path ""
					(reference "C251")
					(unit 1)
				)
			)
		)
	)
	(symbol
		(lib_id "antmicroResistors0402:R_4k7_0402")
		(at 379.73 201.93 90)
		(mirror x)
		(unit 1)
		(exclude_from_sim no)
		(in_bom yes)
		(on_board yes)
		(dnp no)
		(property "Reference" "R196"
			(at 381 203.2 90)
			(effects
				(font
					(size 1.27 1.27)
				)
				(justify right)
			)
		)
		(property "Value" "R_4k7_0402"
			(at 392.43 222.25 0)
			(effects
				(font
					(size 1.27 1.27)
					(thickness 0.15)
				)
				(justify left bottom)
				(hide yes)
			)
		)
		(property "Footprint" "antmicro-footprints:R_0402_1005Metric"
			(at 394.97 222.25 0)
			(effects
				(font
					(size 1.27 1.27)
					(thickness 0.15)
				)
				(justify left bottom)
				(hide yes)
			)
		)
		(property "Datasheet" "https://www.bourns.com/docs/product-datasheets/cr.pdf"
			(at 397.51 222.25 0)
			(effects
				(font
					(size 1.27 1.27)
					(thickness 0.15)
				)
				(justify left bottom)
				(hide yes)
			)
		)
		(property "Description" ""
			(at 379.73 201.93 0)
			(effects
				(font
					(size 1.27 1.27)
				)
			)
		)
		(property "Manufacturer" "Bourns"
			(at 402.59 222.25 0)
			(effects
				(font
					(size 1.27 1.27)
					(thickness 0.15)
				)
				(justify left bottom)
				(hide yes)
			)
		)
		(property "MPN" "CR0402-FX-4701GLF"
			(at 400.05 222.25 0)
			(effects
				(font
					(size 1.27 1.27)
					(thickness 0.15)
				)
				(justify left bottom)
				(hide yes)
			)
		)
		(property "Val" "4k7"
			(at 381 205.74 90)
			(effects
				(font
					(size 1.27 1.27)
					(thickness 0.15)
				)
				(justify right)
			)
		)
		(property "License" "Apache-2.0"
			(at 405.13 222.25 0)
			(effects
				(font
					(size 1.27 1.27)
					(thickness 0.15)
				)
				(justify left bottom)
				(hide yes)
			)
		)
		(property "Author" "Antmicro"
			(at 407.67 222.25 0)
			(effects
				(font
					(size 1.27 1.27)
					(thickness 0.15)
				)
				(justify left bottom)
				(hide yes)
			)
		)
		(property "Tolerance" "1%"
			(at 389.89 222.25 0)
			(effects
				(font
					(size 1.27 1.27)
				)
				(justify left bottom)
				(hide yes)
			)
		)
		(pin "1"
		)
		(pin "2"
		)
		(instances
			(project "k410t-devboard"
				(path ""
					(reference "R196")
					(unit 1)
				)
			)
		)
	)
	(symbol
		(lib_id "antmicropower:PWR_FLAG")
		(at 400.05 83.82 0)
		(unit 1)
		(exclude_from_sim no)
		(in_bom yes)
		(on_board yes)
		(dnp no)
		(property "Reference" "#FLG0103"
			(at 400.05 81.915 0)
			(effects
				(font
					(size 1.27 1.27)
				)
				(hide yes)
			)
		)
		(property "Value" "PWR_FLAG"
			(at 400.05 80.01 0)
			(effects
				(font
					(size 1.27 1.27)
				)
			)
		)
		(property "Footprint" ""
			(at 400.05 83.82 0)
			(effects
				(font
					(size 1.27 1.27)
				)
				(hide yes)
			)
		)
		(property "Datasheet" ""
			(at 400.05 83.82 0)
			(effects
				(font
					(size 1.27 1.27)
				)
				(hide yes)
			)
		)
		(property "Description" ""
			(at 400.05 83.82 0)
			(effects
				(font
					(size 1.27 1.27)
				)
			)
		)
		(pin "1"
		)
		(instances
			(project "k410t-devboard"
				(path ""
					(reference "#FLG0103")
					(unit 1)
				)
			)
		)
	)
	(symbol
		(lib_id "antmicroResistors0402:R_10k_0402")
		(at 309.88 82.55 270)
		(mirror x)
		(unit 1)
		(exclude_from_sim no)
		(in_bom yes)
		(on_board yes)
		(dnp no)
		(property "Reference" "R190"
			(at 308.61 78.74 90)
			(effects
				(font
					(size 1.27 1.27)
				)
				(justify right)
			)
		)
		(property "Value" "R_10k_0402"
			(at 297.18 62.23 0)
			(effects
				(font
					(size 1.27 1.27)
					(thickness 0.15)
				)
				(justify left bottom)
				(hide yes)
			)
		)
		(property "Footprint" "antmicro-footprints:R_0402_1005Metric"
			(at 294.64 62.23 0)
			(effects
				(font
					(size 1.27 1.27)
					(thickness 0.15)
				)
				(justify left bottom)
				(hide yes)
			)
		)
		(property "Datasheet" "https://www.bourns.com/docs/product-datasheets/cr.pdf"
			(at 292.1 62.23 0)
			(effects
				(font
					(size 1.27 1.27)
					(thickness 0.15)
				)
				(justify left bottom)
				(hide yes)
			)
		)
		(property "Description" ""
			(at 309.88 82.55 0)
			(effects
				(font
					(size 1.27 1.27)
				)
			)
		)
		(property "Manufacturer" "Bourns"
			(at 287.02 62.23 0)
			(effects
				(font
					(size 1.27 1.27)
					(thickness 0.15)
				)
				(justify left bottom)
				(hide yes)
			)
		)
		(property "MPN" "CR0402-FX-1002GLF"
			(at 289.56 62.23 0)
			(effects
				(font
					(size 1.27 1.27)
					(thickness 0.15)
				)
				(justify left bottom)
				(hide yes)
			)
		)
		(property "Val" "10k"
			(at 308.61 81.28 90)
			(effects
				(font
					(size 1.27 1.27)
					(thickness 0.15)
				)
				(justify right)
			)
		)
		(property "License" "Apache-2.0"
			(at 284.48 62.23 0)
			(effects
				(font
					(size 1.27 1.27)
					(thickness 0.15)
				)
				(justify left bottom)
				(hide yes)
			)
		)
		(property "Author" "Antmicro"
			(at 281.94 62.23 0)
			(effects
				(font
					(size 1.27 1.27)
					(thickness 0.15)
				)
				(justify left bottom)
				(hide yes)
			)
		)
		(property "Tolerance" "1%"
			(at 299.72 62.23 0)
			(effects
				(font
					(size 1.27 1.27)
				)
				(justify left bottom)
				(hide yes)
			)
		)
		(pin "1"
		)
		(pin "2"
		)
		(instances
			(project "k410t-devboard"
				(path ""
					(reference "R190")
					(unit 1)
				)
			)
		)
	)
	(symbol
		(lib_id "antmicroResonators:Resonator_12MHz_ABM8G")
		(at 147.32 207.01 0)
		(unit 1)
		(exclude_from_sim no)
		(in_bom yes)
		(on_board yes)
		(dnp no)
		(property "Reference" "Y2"
			(at 151.13 200.66 0)
			(effects
				(font
					(size 1.27 1.27)
				)
			)
		)
		(property "Value" "Resonator_12MHz_ABM8G"
			(at 162.56 219.71 0)
			(effects
				(font
					(size 1.27 1.27)
					(thickness 0.15)
				)
				(justify left bottom)
				(hide yes)
			)
		)
		(property "Footprint" "antmicro-footprints:Resonator_SMD_Abracon_ABM8G_3.2x2.5mm"
			(at 162.56 222.25 0)
			(effects
				(font
					(size 1.27 1.27)
					(thickness 0.15)
				)
				(justify left bottom)
				(hide yes)
			)
		)
		(property "Datasheet" "https://abracon.com/Resonators/ABM8G.pdf"
			(at 162.56 224.79 0)
			(effects
				(font
					(size 1.27 1.27)
					(thickness 0.15)
				)
				(justify left bottom)
				(hide yes)
			)
		)
		(property "Description" ""
			(at 147.32 207.01 0)
			(effects
				(font
					(size 1.27 1.27)
				)
			)
		)
		(property "MPN" "ABM8G-12.000MHZ-18-D2Y-T"
			(at 162.56 214.63 0)
			(effects
				(font
					(size 1.27 1.27)
					(thickness 0.15)
				)
				(justify left bottom)
				(hide yes)
			)
		)
		(property "Manufacturer" "Abracon"
			(at 162.56 227.33 0)
			(effects
				(font
					(size 1.27 1.27)
					(thickness 0.15)
				)
				(justify left bottom)
				(hide yes)
			)
		)
		(property "Val" "12 MHz"
			(at 151.13 203.2 0)
			(effects
				(font
					(size 1.27 1.27)
					(thickness 0.15)
				)
			)
		)
		(property "Author" "Antmicro"
			(at 162.56 229.87 0)
			(effects
				(font
					(size 1.27 1.27)
					(thickness 0.15)
				)
				(justify left bottom)
				(hide yes)
			)
		)
		(property "License" "Apache-2.0"
			(at 162.56 232.41 0)
			(effects
				(font
					(size 1.27 1.27)
					(thickness 0.15)
				)
				(justify left bottom)
				(hide yes)
			)
		)
		(pin "1"
		)
		(pin "2"
		)
		(pin "3"
		)
		(pin "4"
		)
		(instances
			(project "k410t-devboard"
				(path ""
					(reference "Y2")
					(unit 1)
				)
			)
		)
	)
	(symbol
		(lib_id "antmicroResistors0402:R_330R_0402")
		(at 80.01 247.65 0)
		(unit 1)
		(exclude_from_sim no)
		(in_bom yes)
		(on_board yes)
		(dnp no)
		(property "Reference" "R151"
			(at 85.09 247.65 0)
			(effects
				(font
					(size 1.524 1.524)
				)
				(justify left bottom)
			)
		)
		(property "Value" "R_330R_0402"
			(at 100.33 260.35 0)
			(effects
				(font
					(size 1.27 1.27)
					(thickness 0.15)
				)
				(justify left bottom)
				(hide yes)
			)
		)
		(property "Footprint" "antmicro-footprints:R_0402_1005Metric"
			(at 100.33 262.89 0)
			(effects
				(font
					(size 1.27 1.27)
					(thickness 0.15)
				)
				(justify left bottom)
				(hide yes)
			)
		)
		(property "Datasheet" "https://www.bourns.com/docs/product-datasheets/cr.pdf"
			(at 100.33 265.43 0)
			(effects
				(font
					(size 1.27 1.27)
					(thickness 0.15)
				)
				(justify left bottom)
				(hide yes)
			)
		)
		(property "Description" ""
			(at 80.01 247.65 0)
			(effects
				(font
					(size 1.27 1.27)
				)
			)
		)
		(property "Manufacturer" "Bourns"
			(at 100.33 270.51 0)
			(effects
				(font
					(size 1.27 1.27)
					(thickness 0.15)
				)
				(justify left bottom)
				(hide yes)
			)
		)
		(property "MPN" "CR0402-FX-3300GLF"
			(at 100.33 267.97 0)
			(effects
				(font
					(size 1.27 1.27)
					(thickness 0.15)
				)
				(justify left bottom)
				(hide yes)
			)
		)
		(property "Val" "330R"
			(at 74.93 247.65 0)
			(effects
				(font
					(size 1.27 1.27)
					(thickness 0.15)
				)
				(justify left bottom)
			)
		)
		(property "License" "Apache-2.0"
			(at 100.33 273.05 0)
			(effects
				(font
					(size 1.27 1.27)
					(thickness 0.15)
				)
				(justify left bottom)
				(hide yes)
			)
		)
		(property "Author" "Antmicro"
			(at 100.33 275.59 0)
			(effects
				(font
					(size 1.27 1.27)
					(thickness 0.15)
				)
				(justify left bottom)
				(hide yes)
			)
		)
		(property "Tolerance" "1%"
			(at 100.33 257.81 0)
			(effects
				(font
					(size 1.27 1.27)
				)
				(justify left bottom)
				(hide yes)
			)
		)
		(pin "1"
		)
		(pin "2"
		)
		(instances
			(project "k410t-devboard"
				(path ""
					(reference "R151")
					(unit 1)
				)
			)
		)
	)
	(symbol
		(lib_id "antmicroResistors0402:R_33R_0402")
		(at 238.76 210.82 0)
		(unit 1)
		(exclude_from_sim no)
		(in_bom yes)
		(on_board yes)
		(dnp no)
		(property "Reference" "R164"
			(at 243.84 209.55 0)
			(effects
				(font
					(size 1.27 1.27)
				)
				(justify left)
			)
		)
		(property "Value" "R_33R_0402"
			(at 259.08 223.52 0)
			(effects
				(font
					(size 1.27 1.27)
					(thickness 0.15)
				)
				(justify left bottom)
				(hide yes)
			)
		)
		(property "Footprint" "antmicro-footprints:R_0402_1005Metric"
			(at 259.08 226.06 0)
			(effects
				(font
					(size 1.27 1.27)
					(thickness 0.15)
				)
				(justify left bottom)
				(hide yes)
			)
		)
		(property "Datasheet" "https://www.bourns.com/docs/product-datasheets/cr.pdf"
			(at 259.08 228.6 0)
			(effects
				(font
					(size 1.27 1.27)
					(thickness 0.15)
				)
				(justify left bottom)
				(hide yes)
			)
		)
		(property "Description" ""
			(at 238.76 210.82 0)
			(effects
				(font
					(size 1.27 1.27)
				)
			)
		)
		(property "Manufacturer" "Bourns"
			(at 259.08 233.68 0)
			(effects
				(font
					(size 1.27 1.27)
					(thickness 0.15)
				)
				(justify left bottom)
				(hide yes)
			)
		)
		(property "MPN" "CR0402-FX-33R0GLF"
			(at 259.08 231.14 0)
			(effects
				(font
					(size 1.27 1.27)
					(thickness 0.15)
				)
				(justify left bottom)
				(hide yes)
			)
		)
		(property "Val" "33R"
			(at 234.95 210.82 0)
			(effects
				(font
					(size 1.27 1.27)
					(thickness 0.15)
				)
				(justify left bottom)
			)
		)
		(property "License" "Apache-2.0"
			(at 259.08 236.22 0)
			(effects
				(font
					(size 1.27 1.27)
					(thickness 0.15)
				)
				(justify left bottom)
				(hide yes)
			)
		)
		(property "Author" "Antmicro"
			(at 259.08 238.76 0)
			(effects
				(font
					(size 1.27 1.27)
					(thickness 0.15)
				)
				(justify left bottom)
				(hide yes)
			)
		)
		(property "Tolerance" "1%"
			(at 259.08 220.98 0)
			(effects
				(font
					(size 1.27 1.27)
				)
				(justify left bottom)
				(hide yes)
			)
		)
		(pin "1"
		)
		(pin "2"
		)
		(instances
			(project "k410t-devboard"
				(path ""
					(reference "R164")
					(unit 1)
				)
			)
		)
	)
	(symbol
		(lib_id "antmicroResistors0402:R_10k_0402")
		(at 392.43 45.72 0)
		(mirror x)
		(unit 1)
		(exclude_from_sim no)
		(in_bom yes)
		(on_board yes)
		(dnp no)
		(property "Reference" "R194"
			(at 400.05 44.45 0)
			(effects
				(font
					(size 1.27 1.27)
				)
			)
		)
		(property "Value" "R_10k_0402"
			(at 412.75 33.02 0)
			(effects
				(font
					(size 1.27 1.27)
					(thickness 0.15)
				)
				(justify left bottom)
				(hide yes)
			)
		)
		(property "Footprint" "antmicro-footprints:R_0402_1005Metric"
			(at 412.75 30.48 0)
			(effects
				(font
					(size 1.27 1.27)
					(thickness 0.15)
				)
				(justify left bottom)
				(hide yes)
			)
		)
		(property "Datasheet" "https://www.bourns.com/docs/product-datasheets/cr.pdf"
			(at 412.75 27.94 0)
			(effects
				(font
					(size 1.27 1.27)
					(thickness 0.15)
				)
				(justify left bottom)
				(hide yes)
			)
		)
		(property "Description" ""
			(at 392.43 45.72 0)
			(effects
				(font
					(size 1.27 1.27)
				)
			)
		)
		(property "Manufacturer" "Bourns"
			(at 412.75 22.86 0)
			(effects
				(font
					(size 1.27 1.27)
					(thickness 0.15)
				)
				(justify left bottom)
				(hide yes)
			)
		)
		(property "MPN" "CR0402-FX-1002GLF"
			(at 412.75 25.4 0)
			(effects
				(font
					(size 1.27 1.27)
					(thickness 0.15)
				)
				(justify left bottom)
				(hide yes)
			)
		)
		(property "Val" "10k"
			(at 390.525 44.45 0)
			(effects
				(font
					(size 1.27 1.27)
					(thickness 0.15)
				)
			)
		)
		(property "License" "Apache-2.0"
			(at 412.75 20.32 0)
			(effects
				(font
					(size 1.27 1.27)
					(thickness 0.15)
				)
				(justify left bottom)
				(hide yes)
			)
		)
		(property "Author" "Antmicro"
			(at 412.75 17.78 0)
			(effects
				(font
					(size 1.27 1.27)
					(thickness 0.15)
				)
				(justify left bottom)
				(hide yes)
			)
		)
		(property "Tolerance" "1%"
			(at 412.75 35.56 0)
			(effects
				(font
					(size 1.27 1.27)
				)
				(justify left bottom)
				(hide yes)
			)
		)
		(pin "1"
		)
		(pin "2"
		)
		(instances
			(project "k410t-devboard"
				(path ""
					(reference "R194")
					(unit 1)
				)
			)
		)
	)
	(symbol
		(lib_id "antmicropower:GND")
		(at 284.48 52.07 0)
		(unit 1)
		(exclude_from_sim no)
		(in_bom yes)
		(on_board yes)
		(dnp no)
		(property "Reference" "#PWR0255"
			(at 284.48 58.42 0)
			(effects
				(font
					(size 1.27 1.27)
				)
				(hide yes)
			)
		)
		(property "Value" "GND"
			(at 284.48 55.88 0)
			(effects
				(font
					(size 1.27 1.27)
				)
			)
		)
		(property "Footprint" ""
			(at 293.37 59.69 0)
			(effects
				(font
					(size 1.27 1.27)
					(thickness 0.15)
				)
				(justify left bottom)
				(hide yes)
			)
		)
		(property "Datasheet" ""
			(at 293.37 64.77 0)
			(effects
				(font
					(size 1.27 1.27)
					(thickness 0.15)
				)
				(justify left bottom)
				(hide yes)
			)
		)
		(property "Description" ""
			(at 284.48 52.07 0)
			(effects
				(font
					(size 1.27 1.27)
				)
			)
		)
		(property "Author" "Antmicro"
			(at 293.37 59.69 0)
			(effects
				(font
					(size 1.27 1.27)
					(thickness 0.15)
				)
				(justify left bottom)
				(hide yes)
			)
		)
		(property "License" "Apache-2.0"
			(at 293.37 62.23 0)
			(effects
				(font
					(size 1.27 1.27)
					(thickness 0.15)
				)
				(justify left bottom)
				(hide yes)
			)
		)
		(pin "1"
		)
		(instances
			(project "k410t-devboard"
				(path ""
					(reference "#PWR0255")
					(unit 1)
				)
			)
		)
	)
	(symbol
		(lib_id "antmicropower:+5V")
		(at 21.59 67.31 0)
		(unit 1)
		(exclude_from_sim no)
		(in_bom yes)
		(on_board yes)
		(dnp no)
		(property "Reference" "#PWR0185"
			(at 21.59 71.12 0)
			(effects
				(font
					(size 1.27 1.27)
				)
				(hide yes)
			)
		)
		(property "Value" "+5V"
			(at 21.59 63.5 0)
			(effects
				(font
					(size 1.27 1.27)
				)
			)
		)
		(property "Footprint" ""
			(at 21.59 67.31 0)
			(effects
				(font
					(size 1.27 1.27)
				)
				(hide yes)
			)
		)
		(property "Datasheet" ""
			(at 21.59 67.31 0)
			(effects
				(font
					(size 1.27 1.27)
				)
				(hide yes)
			)
		)
		(property "Description" ""
			(at 21.59 67.31 0)
			(effects
				(font
					(size 1.27 1.27)
				)
			)
		)
		(property "Author" "Antmicro"
			(at 36.83 74.93 0)
			(effects
				(font
					(size 1.27 1.27)
					(thickness 0.15)
				)
				(justify left bottom)
				(hide yes)
			)
		)
		(property "License" "Apache-2.0"
			(at 36.83 77.47 0)
			(effects
				(font
					(size 1.27 1.27)
					(thickness 0.15)
				)
				(justify left bottom)
				(hide yes)
			)
		)
		(pin "1"
		)
		(instances
			(project "k410t-devboard"
				(path ""
					(reference "#PWR0185")
					(unit 1)
				)
			)
		)
	)
	(symbol
		(lib_id "antmicroCapacitors0402:C_100n_0402")
		(at 147.32 88.9 90)
		(unit 1)
		(exclude_from_sim no)
		(in_bom yes)
		(on_board yes)
		(dnp no)
		(fields_autoplaced yes)
		(property "Reference" "C227"
			(at 150.495 85.0835 90)
			(effects
				(font
					(size 1.27 1.27)
				)
				(justify right)
			)
		)
		(property "Value" "C_100n_0402"
			(at 157.48 68.58 0)
			(effects
				(font
					(size 1.27 1.27)
					(thickness 0.15)
				)
				(justify left bottom)
				(hide yes)
			)
		)
		(property "Footprint" "antmicro-footprints:C_0402_1005Metric"
			(at 160.02 68.58 0)
			(effects
				(font
					(size 1.27 1.27)
					(thickness 0.15)
				)
				(justify left bottom)
				(hide yes)
			)
		)
		(property "Datasheet" "https://www.murata.com/products/productdetail?partno=GRM155R61H104KE14%23"
			(at 162.56 68.58 0)
			(effects
				(font
					(size 1.27 1.27)
					(thickness 0.15)
				)
				(justify left bottom)
				(hide yes)
			)
		)
		(property "Description" ""
			(at 147.32 88.9 0)
			(effects
				(font
					(size 1.27 1.27)
				)
			)
		)
		(property "Manufacturer" "Murata"
			(at 167.64 68.58 0)
			(effects
				(font
					(size 1.27 1.27)
					(thickness 0.15)
				)
				(justify left bottom)
				(hide yes)
			)
		)
		(property "MPN" "GRM155R61H104KE14D"
			(at 165.1 68.58 0)
			(effects
				(font
					(size 1.27 1.27)
					(thickness 0.15)
				)
				(justify left bottom)
				(hide yes)
			)
		)
		(property "Val" "100n"
			(at 150.495 87.6235 90)
			(effects
				(font
					(size 1.27 1.27)
					(thickness 0.15)
				)
				(justify right)
			)
		)
		(property "License" "Apache-2.0"
			(at 170.18 68.58 0)
			(effects
				(font
					(size 1.27 1.27)
					(thickness 0.15)
				)
				(justify left bottom)
				(hide yes)
			)
		)
		(property "Author" "Antmicro"
			(at 172.72 68.58 0)
			(effects
				(font
					(size 1.27 1.27)
					(thickness 0.15)
				)
				(justify left bottom)
				(hide yes)
			)
		)
		(property "Voltage" "50V"
			(at 175.26 68.58 0)
			(effects
				(font
					(size 1.27 1.27)
				)
				(justify left bottom)
				(hide yes)
			)
		)
		(property "Dielectric" "X5R"
			(at 177.8 68.58 0)
			(effects
				(font
					(size 1.27 1.27)
				)
				(justify left bottom)
				(hide yes)
			)
		)
		(pin "1"
		)
		(pin "2"
		)
		(instances
			(project "k410t-devboard"
				(path ""
					(reference "C227")
					(unit 1)
				)
			)
		)
	)
	(symbol
		(lib_id "antmicroLEDIndicationDiscrete:LED_G_0603_KP-1608CGCK")
		(at 53.34 245.11 0)
		(unit 1)
		(exclude_from_sim no)
		(in_bom yes)
		(on_board yes)
		(dnp no)
		(property "Reference" "D27"
			(at 64.135 243.205 0)
			(effects
				(font
					(size 1.27 1.27)
				)
				(justify right)
			)
		)
		(property "Value" "LED_G_0603_KP-1608CGCK"
			(at 60.96 244.475 0)
			(effects
				(font
					(size 1.27 1.27)
					(thickness 0.15)
				)
				(justify left bottom)
				(hide yes)
			)
		)
		(property "Footprint" "antmicro-footprints:LED_0603_1608Metric_G"
			(at 76.2 255.27 0)
			(effects
				(font
					(size 1.27 1.27)
					(thickness 0.15)
				)
				(justify left bottom)
				(hide yes)
			)
		)
		(property "Datasheet" "http://www.kingbright.com/attachments/file/psearch//000/00/00/KP-1608CGCK(Ver.23B).pdf"
			(at 76.2 257.81 0)
			(effects
				(font
					(size 1.27 1.27)
					(thickness 0.15)
				)
				(justify left bottom)
				(hide yes)
			)
		)
		(property "Description" ""
			(at 53.34 245.11 0)
			(effects
				(font
					(size 1.27 1.27)
				)
			)
		)
		(property "MPN" "KP-1608CGCK"
			(at 76.2 260.35 0)
			(effects
				(font
					(size 1.27 1.27)
					(thickness 0.15)
				)
				(justify left bottom)
				(hide yes)
			)
		)
		(property "Manufacturer" "Kingbright"
			(at 76.2 262.89 0)
			(effects
				(font
					(size 1.27 1.27)
					(thickness 0.15)
				)
				(justify left bottom)
				(hide yes)
			)
		)
		(property "Author" "Antmicro"
			(at 76.2 265.43 0)
			(effects
				(font
					(size 1.27 1.27)
					(thickness 0.15)
				)
				(justify left bottom)
				(hide yes)
			)
		)
		(property "License" "Apache-2.0"
			(at 76.2 267.97 0)
			(effects
				(font
					(size 1.27 1.27)
					(thickness 0.15)
				)
				(justify left bottom)
				(hide yes)
			)
		)
		(property "Color" "Green"
			(at 48.26 243.84 0)
			(effects
				(font
					(size 1.27 1.27)
				)
				(justify left bottom)
			)
		)
		(pin "1"
		)
		(pin "2"
		)
		(instances
			(project "k410t-devboard"
				(path ""
					(reference "D27")
					(unit 1)
				)
			)
		)
	)
	(symbol
		(lib_id "antmicroResistors0402:R_10k_0402")
		(at 309.88 91.44 270)
		(mirror x)
		(unit 1)
		(exclude_from_sim no)
		(in_bom yes)
		(on_board yes)
		(dnp no)
		(property "Reference" "R191"
			(at 308.61 87.63 90)
			(effects
				(font
					(size 1.27 1.27)
				)
				(justify right)
			)
		)
		(property "Value" "R_10k_0402"
			(at 297.18 71.12 0)
			(effects
				(font
					(size 1.27 1.27)
					(thickness 0.15)
				)
				(justify left bottom)
				(hide yes)
			)
		)
		(property "Footprint" "antmicro-footprints:R_0402_1005Metric"
			(at 294.64 71.12 0)
			(effects
				(font
					(size 1.27 1.27)
					(thickness 0.15)
				)
				(justify left bottom)
				(hide yes)
			)
		)
		(property "Datasheet" "https://www.bourns.com/docs/product-datasheets/cr.pdf"
			(at 292.1 71.12 0)
			(effects
				(font
					(size 1.27 1.27)
					(thickness 0.15)
				)
				(justify left bottom)
				(hide yes)
			)
		)
		(property "Description" ""
			(at 309.88 91.44 0)
			(effects
				(font
					(size 1.27 1.27)
				)
			)
		)
		(property "Manufacturer" "Bourns"
			(at 287.02 71.12 0)
			(effects
				(font
					(size 1.27 1.27)
					(thickness 0.15)
				)
				(justify left bottom)
				(hide yes)
			)
		)
		(property "MPN" "CR0402-FX-1002GLF"
			(at 289.56 71.12 0)
			(effects
				(font
					(size 1.27 1.27)
					(thickness 0.15)
				)
				(justify left bottom)
				(hide yes)
			)
		)
		(property "Val" "10k"
			(at 308.61 90.17 90)
			(effects
				(font
					(size 1.27 1.27)
					(thickness 0.15)
				)
				(justify right)
			)
		)
		(property "License" "Apache-2.0"
			(at 284.48 71.12 0)
			(effects
				(font
					(size 1.27 1.27)
					(thickness 0.15)
				)
				(justify left bottom)
				(hide yes)
			)
		)
		(property "Author" "Antmicro"
			(at 281.94 71.12 0)
			(effects
				(font
					(size 1.27 1.27)
					(thickness 0.15)
				)
				(justify left bottom)
				(hide yes)
			)
		)
		(property "Tolerance" "1%"
			(at 299.72 71.12 0)
			(effects
				(font
					(size 1.27 1.27)
				)
				(justify left bottom)
				(hide yes)
			)
		)
		(pin "1"
		)
		(pin "2"
		)
		(instances
			(project "k410t-devboard"
				(path ""
					(reference "R191")
					(unit 1)
				)
			)
		)
	)
	(symbol
		(lib_id "antmicroResistors0402:R_33R_0402")
		(at 341.63 146.05 0)
		(unit 1)
		(exclude_from_sim no)
		(in_bom yes)
		(on_board yes)
		(dnp no)
		(property "Reference" "R177"
			(at 349.25 144.78 0)
			(effects
				(font
					(size 1.27 1.27)
				)
			)
		)
		(property "Value" "R_33R_0402"
			(at 361.95 158.75 0)
			(effects
				(font
					(size 1.27 1.27)
					(thickness 0.15)
				)
				(justify left bottom)
				(hide yes)
			)
		)
		(property "Footprint" "antmicro-footprints:R_0402_1005Metric"
			(at 361.95 161.29 0)
			(effects
				(font
					(size 1.27 1.27)
					(thickness 0.15)
				)
				(justify left bottom)
				(hide yes)
			)
		)
		(property "Datasheet" "https://www.bourns.com/docs/product-datasheets/cr.pdf"
			(at 361.95 163.83 0)
			(effects
				(font
					(size 1.27 1.27)
					(thickness 0.15)
				)
				(justify left bottom)
				(hide yes)
			)
		)
		(property "Description" ""
			(at 341.63 146.05 0)
			(effects
				(font
					(size 1.27 1.27)
				)
			)
		)
		(property "Manufacturer" "Bourns"
			(at 361.95 168.91 0)
			(effects
				(font
					(size 1.27 1.27)
					(thickness 0.15)
				)
				(justify left bottom)
				(hide yes)
			)
		)
		(property "MPN" "CR0402-FX-33R0GLF"
			(at 361.95 166.37 0)
			(effects
				(font
					(size 1.27 1.27)
					(thickness 0.15)
				)
				(justify left bottom)
				(hide yes)
			)
		)
		(property "Val" "33R"
			(at 339.725 144.78 0)
			(effects
				(font
					(size 1.27 1.27)
					(thickness 0.15)
				)
			)
		)
		(property "License" "Apache-2.0"
			(at 361.95 171.45 0)
			(effects
				(font
					(size 1.27 1.27)
					(thickness 0.15)
				)
				(justify left bottom)
				(hide yes)
			)
		)
		(property "Author" "Antmicro"
			(at 361.95 173.99 0)
			(effects
				(font
					(size 1.27 1.27)
					(thickness 0.15)
				)
				(justify left bottom)
				(hide yes)
			)
		)
		(property "Tolerance" "1%"
			(at 361.95 156.21 0)
			(effects
				(font
					(size 1.27 1.27)
				)
				(justify left bottom)
				(hide yes)
			)
		)
		(pin "1"
		)
		(pin "2"
		)
		(instances
			(project "k410t-devboard"
				(path ""
					(reference "R177")
					(unit 1)
				)
			)
		)
	)
	(symbol
		(lib_id "antmicroResistors0402:R_33R_0402")
		(at 340.36 182.88 0)
		(unit 1)
		(exclude_from_sim no)
		(in_bom yes)
		(on_board yes)
		(dnp no)
		(property "Reference" "R184"
			(at 347.98 181.61 0)
			(effects
				(font
					(size 1.27 1.27)
				)
			)
		)
		(property "Value" "R_33R_0402"
			(at 360.68 195.58 0)
			(effects
				(font
					(size 1.27 1.27)
					(thickness 0.15)
				)
				(justify left bottom)
				(hide yes)
			)
		)
		(property "Footprint" "antmicro-footprints:R_0402_1005Metric"
			(at 360.68 198.12 0)
			(effects
				(font
					(size 1.27 1.27)
					(thickness 0.15)
				)
				(justify left bottom)
				(hide yes)
			)
		)
		(property "Datasheet" "https://www.bourns.com/docs/product-datasheets/cr.pdf"
			(at 360.68 200.66 0)
			(effects
				(font
					(size 1.27 1.27)
					(thickness 0.15)
				)
				(justify left bottom)
				(hide yes)
			)
		)
		(property "Description" ""
			(at 340.36 182.88 0)
			(effects
				(font
					(size 1.27 1.27)
				)
			)
		)
		(property "Manufacturer" "Bourns"
			(at 360.68 205.74 0)
			(effects
				(font
					(size 1.27 1.27)
					(thickness 0.15)
				)
				(justify left bottom)
				(hide yes)
			)
		)
		(property "MPN" "CR0402-FX-33R0GLF"
			(at 360.68 203.2 0)
			(effects
				(font
					(size 1.27 1.27)
					(thickness 0.15)
				)
				(justify left bottom)
				(hide yes)
			)
		)
		(property "Val" "33R"
			(at 338.455 181.61 0)
			(effects
				(font
					(size 1.27 1.27)
					(thickness 0.15)
				)
			)
		)
		(property "License" "Apache-2.0"
			(at 360.68 208.28 0)
			(effects
				(font
					(size 1.27 1.27)
					(thickness 0.15)
				)
				(justify left bottom)
				(hide yes)
			)
		)
		(property "Author" "Antmicro"
			(at 360.68 210.82 0)
			(effects
				(font
					(size 1.27 1.27)
					(thickness 0.15)
				)
				(justify left bottom)
				(hide yes)
			)
		)
		(property "Tolerance" "1%"
			(at 360.68 193.04 0)
			(effects
				(font
					(size 1.27 1.27)
				)
				(justify left bottom)
				(hide yes)
			)
		)
		(pin "1"
		)
		(pin "2"
		)
		(instances
			(project "k410t-devboard"
				(path ""
					(reference "R184")
					(unit 1)
				)
			)
		)
	)
	(symbol
		(lib_id "antmicroResistors0402:R_33R_0402")
		(at 341.63 151.13 0)
		(unit 1)
		(exclude_from_sim no)
		(in_bom yes)
		(on_board yes)
		(dnp no)
		(property "Reference" "R179"
			(at 349.25 149.86 0)
			(effects
				(font
					(size 1.27 1.27)
				)
			)
		)
		(property "Value" "R_33R_0402"
			(at 361.95 163.83 0)
			(effects
				(font
					(size 1.27 1.27)
					(thickness 0.15)
				)
				(justify left bottom)
				(hide yes)
			)
		)
		(property "Footprint" "antmicro-footprints:R_0402_1005Metric"
			(at 361.95 166.37 0)
			(effects
				(font
					(size 1.27 1.27)
					(thickness 0.15)
				)
				(justify left bottom)
				(hide yes)
			)
		)
		(property "Datasheet" "https://www.bourns.com/docs/product-datasheets/cr.pdf"
			(at 361.95 168.91 0)
			(effects
				(font
					(size 1.27 1.27)
					(thickness 0.15)
				)
				(justify left bottom)
				(hide yes)
			)
		)
		(property "Description" ""
			(at 341.63 151.13 0)
			(effects
				(font
					(size 1.27 1.27)
				)
			)
		)
		(property "Manufacturer" "Bourns"
			(at 361.95 173.99 0)
			(effects
				(font
					(size 1.27 1.27)
					(thickness 0.15)
				)
				(justify left bottom)
				(hide yes)
			)
		)
		(property "MPN" "CR0402-FX-33R0GLF"
			(at 361.95 171.45 0)
			(effects
				(font
					(size 1.27 1.27)
					(thickness 0.15)
				)
				(justify left bottom)
				(hide yes)
			)
		)
		(property "Val" "33R"
			(at 339.725 149.86 0)
			(effects
				(font
					(size 1.27 1.27)
					(thickness 0.15)
				)
			)
		)
		(property "License" "Apache-2.0"
			(at 361.95 176.53 0)
			(effects
				(font
					(size 1.27 1.27)
					(thickness 0.15)
				)
				(justify left bottom)
				(hide yes)
			)
		)
		(property "Author" "Antmicro"
			(at 361.95 179.07 0)
			(effects
				(font
					(size 1.27 1.27)
					(thickness 0.15)
				)
				(justify left bottom)
				(hide yes)
			)
		)
		(property "Tolerance" "1%"
			(at 361.95 161.29 0)
			(effects
				(font
					(size 1.27 1.27)
				)
				(justify left bottom)
				(hide yes)
			)
		)
		(pin "1"
		)
		(pin "2"
		)
		(instances
			(project "k410t-devboard"
				(path ""
					(reference "R179")
					(unit 1)
				)
			)
		)
	)
	(symbol
		(lib_id "antmicropower:PWR_FLAG")
		(at 173.99 124.46 0)
		(unit 1)
		(exclude_from_sim no)
		(in_bom yes)
		(on_board yes)
		(dnp no)
		(property "Reference" "#FLG06"
			(at 173.99 122.555 0)
			(effects
				(font
					(size 1.27 1.27)
				)
				(hide yes)
			)
		)
		(property "Value" "PWR_FLAG"
			(at 173.99 120.65 0)
			(effects
				(font
					(size 1.27 1.27)
				)
			)
		)
		(property "Footprint" ""
			(at 173.99 124.46 0)
			(effects
				(font
					(size 1.27 1.27)
				)
				(hide yes)
			)
		)
		(property "Datasheet" ""
			(at 173.99 124.46 0)
			(effects
				(font
					(size 1.27 1.27)
				)
				(hide yes)
			)
		)
		(property "Description" ""
			(at 173.99 124.46 0)
			(effects
				(font
					(size 1.27 1.27)
				)
			)
		)
		(pin "1"
		)
		(instances
			(project "k410t-devboard"
				(path ""
					(reference "#FLG06")
					(unit 1)
				)
			)
		)
	)
	(symbol
		(lib_id "antmicroTransistorsFETsMOSFETsSingle:BSS138PW")
		(at 245.11 245.11 0)
		(unit 1)
		(exclude_from_sim no)
		(in_bom yes)
		(on_board yes)
		(dnp no)
		(fields_autoplaced yes)
		(property "Reference" "Q17"
			(at 256.54 241.3 0)
			(effects
				(font
					(size 1.27 1.27)
				)
				(justify left)
			)
		)
		(property "Value" "BSS138PW"
			(at 255.905 243.8399 0)
			(effects
				(font
					(size 1.27 1.27)
					(thickness 0.15)
				)
				(justify left)
				(hide yes)
			)
		)
		(property "Footprint" "antmicro-footprints:SC70-3"
			(at 267.97 256.54 0)
			(effects
				(font
					(size 1.27 1.27)
					(thickness 0.15)
				)
				(justify left bottom)
				(hide yes)
			)
		)
		(property "Datasheet" "https://assets.nexperia.com/documents/data-sheet/BSS138PW.pdf"
			(at 267.97 259.08 0)
			(effects
				(font
					(size 1.27 1.27)
					(thickness 0.15)
				)
				(justify left bottom)
				(hide yes)
			)
		)
		(property "Description" ""
			(at 245.11 245.11 0)
			(effects
				(font
					(size 1.27 1.27)
				)
			)
		)
		(property "MPN" "BSS138PW"
			(at 256.54 243.84 0)
			(effects
				(font
					(size 1.27 1.27)
					(thickness 0.15)
				)
				(justify left)
			)
		)
		(property "Manufacturer" "Nexperia"
			(at 267.97 264.16 0)
			(effects
				(font
					(size 1.27 1.27)
					(thickness 0.15)
				)
				(justify left bottom)
				(hide yes)
			)
		)
		(property "Author" "Antmicro"
			(at 267.97 266.7 0)
			(effects
				(font
					(size 1.27 1.27)
					(thickness 0.15)
				)
				(justify left bottom)
				(hide yes)
			)
		)
		(property "License" "Apache-2.0"
			(at 267.97 269.24 0)
			(effects
				(font
					(size 1.27 1.27)
					(thickness 0.15)
				)
				(justify left bottom)
				(hide yes)
			)
		)
		(pin "1"
		)
		(pin "2"
		)
		(pin "3"
		)
		(instances
			(project "k410t-devboard"
				(path ""
					(reference "Q17")
					(unit 1)
				)
			)
		)
	)
	(symbol
		(lib_id "antmicroResistors0402:R_47k_0402")
		(at 346.71 138.43 180)
		(unit 1)
		(exclude_from_sim no)
		(in_bom yes)
		(on_board yes)
		(dnp no)
		(property "Reference" "R175"
			(at 344.17 133.35 0)
			(effects
				(font
					(size 1.27 1.27)
				)
			)
		)
		(property "Value" "R_47k_0402"
			(at 326.39 125.73 0)
			(effects
				(font
					(size 1.27 1.27)
					(thickness 0.15)
				)
				(justify left bottom)
				(hide yes)
			)
		)
		(property "Footprint" "antmicro-footprints:R_0402_1005Metric"
			(at 326.39 123.19 0)
			(effects
				(font
					(size 1.27 1.27)
					(thickness 0.15)
				)
				(justify left bottom)
				(hide yes)
			)
		)
		(property "Datasheet" "https://www.bourns.com/docs/product-datasheets/cr.pdf"
			(at 326.39 120.65 0)
			(effects
				(font
					(size 1.27 1.27)
					(thickness 0.15)
				)
				(justify left bottom)
				(hide yes)
			)
		)
		(property "Description" ""
			(at 346.71 138.43 0)
			(effects
				(font
					(size 1.27 1.27)
				)
			)
		)
		(property "Manufacturer" "Bourns"
			(at 326.39 115.57 0)
			(effects
				(font
					(size 1.27 1.27)
					(thickness 0.15)
				)
				(justify left bottom)
				(hide yes)
			)
		)
		(property "MPN" "CR0402-FX-4702GLF"
			(at 326.39 118.11 0)
			(effects
				(font
					(size 1.27 1.27)
					(thickness 0.15)
				)
				(justify left bottom)
				(hide yes)
			)
		)
		(property "Val" "47k"
			(at 344.17 135.89 0)
			(effects
				(font
					(size 1.27 1.27)
					(thickness 0.15)
				)
			)
		)
		(property "License" "Apache-2.0"
			(at 326.39 113.03 0)
			(effects
				(font
					(size 1.27 1.27)
					(thickness 0.15)
				)
				(justify left bottom)
				(hide yes)
			)
		)
		(property "Author" "Antmicro"
			(at 326.39 110.49 0)
			(effects
				(font
					(size 1.27 1.27)
					(thickness 0.15)
				)
				(justify left bottom)
				(hide yes)
			)
		)
		(property "Tolerance" "1%"
			(at 326.39 128.27 0)
			(effects
				(font
					(size 1.27 1.27)
				)
				(justify left bottom)
				(hide yes)
			)
		)
		(pin "1"
		)
		(pin "2"
		)
		(instances
			(project "k410t-devboard"
				(path ""
					(reference "R175")
					(unit 1)
				)
			)
		)
	)
)
